FILE_TYPE = MACRO_DRAWING;
SET COLOR_WIRE YELLOW;
SET COLOR_PROP ORANGE;
SET COLOR_DOT WHITE;
SET COLOR_ARC YELLOW;
SET COLOR_BODY GREEN;
SET COLOR_NOTE PURPLE;
SET PROP_DISPLAY VALUE;
SET PAGE_NUMBER P127;
FORCEADD OFFPAGE_OUT..1
R 2
(-11000 5150);
FORCEPROP 2 LAST $XR0 9D10< 
J 0
(-11183 5150);
DISPLAY 0.638298 (-11183 5150);
PAINT MONO (-11183 5150);
FORCEPROP 2 LAST $XR1 10J7< 
J 0
(-11363 5150);
DISPLAY 0.638298 (-11363 5150);
PAINT MONO (-11363 5150);
FORCEPROP 2 LAST PATH I101
J 0
(-11100 5200);
DISPLAY 1.021277 (-11100 5200);
DISPLAY INVISIBLE (-11100 5200);
FORCEPROP 1 LAST OFFPAGE TRUE
J 2
(-11010 5205);
DISPLAY 0.808511 (-11010 5205);
PAINT GREEN (-11010 5205);
DISPLAY INVISIBLE (-11010 5205);
FORCEPROP 2 LAST CDS_LIB cls
J 2
(-11000 5150);
PAINT MONO (-11000 5150);
DISPLAY INVISIBLE (-11000 5150);
FORCEPROP 1 LAST CDS_LMAN_SYM_OUTLINE -50,50,50,-50
J 2
(-11000 5150);
DISPLAY 0.468085 (-11000 5150);
PAINT GREEN (-11000 5150);
DISPLAY INVISIBLE (-11000 5150);
FORCEPROP 1 LAST BODY_TYPE COMMENT
J 2
(-11010 5285);
DISPLAY 0.808511 (-11010 5285);
PAINT GREEN (-11010 5285);
DISPLAY INVISIBLE (-11010 5285);
FORCEADD GND_SG..1
(-9050 5500);
FORCEPROP 3 LASTPIN (-9000 5550) SIG_NAME SG\g
J 0
(-8990 5560);
DISPLAY 0.659574 (-8990 5560);
PAINT MONO (-8990 5560);
DISPLAY INVISIBLE (-8990 5560);
FORCEPROP 1 LAST HDL_POWER SG
J 1
(-8995 5405);
DISPLAY 0.808511 (-8995 5405);
PAINT GREEN (-8995 5405);
FORCEPROP 1 LAST PATH I106
J 0
(-9015 5500);
DISPLAY 0.808511 (-9015 5500);
PAINT GREEN (-9015 5500);
DISPLAY INVISIBLE (-9015 5500);
FORCEPROP 1 LAST BODY_TYPE PLUMBING
J 0
(-9035 5485);
DISPLAY 0.808511 (-9035 5485);
PAINT GREEN (-9035 5485);
DISPLAY INVISIBLE (-9035 5485);
FORCEPROP 2 LAST CDS_LIB cls
J 0
(-9050 5500);
PAINT MONO (-9050 5500);
DISPLAY INVISIBLE (-9050 5500);
FORCEPROP 1 LAST CDS_LMAN_SYM_OUTLINE 0,0,100,-50
J 0
(-9050 5500);
DISPLAY 0.468085 (-9050 5500);
PAINT GREEN (-9050 5500);
DISPLAY INVISIBLE (-9050 5500);
FORCEADD GND_SG..1
(-6350 5750);
FORCEPROP 3 LASTPIN (-6300 5800) SIG_NAME SG\g
J 0
(-6290 5810);
DISPLAY 0.659574 (-6290 5810);
PAINT MONO (-6290 5810);
DISPLAY INVISIBLE (-6290 5810);
FORCEPROP 1 LAST HDL_POWER SG
J 1
(-6295 5655);
DISPLAY 0.808511 (-6295 5655);
PAINT GREEN (-6295 5655);
FORCEPROP 1 LAST PATH I130
J 0
(-6315 5750);
DISPLAY 0.808511 (-6315 5750);
PAINT GREEN (-6315 5750);
DISPLAY INVISIBLE (-6315 5750);
FORCEPROP 1 LAST BODY_TYPE PLUMBING
J 0
(-6335 5735);
DISPLAY 0.808511 (-6335 5735);
PAINT GREEN (-6335 5735);
DISPLAY INVISIBLE (-6335 5735);
FORCEPROP 1 LAST CDS_LMAN_SYM_OUTLINE 0,0,100,-50
J 0
(-6350 5750);
DISPLAY 0.468085 (-6350 5750);
PAINT GREEN (-6350 5750);
DISPLAY INVISIBLE (-6350 5750);
FORCEPROP 2 LAST CDS_LIB cls
J 0
(-6350 5750);
PAINT MONO (-6350 5750);
DISPLAY INVISIBLE (-6350 5750);
FORCEADD OFFPAGE_OUT..1
(-4300 5150);
FORCEPROP 2 LAST $XR0 24H7< 
J 0
(-4245 5150);
DISPLAY 0.638298 (-4245 5150);
PAINT MONO (-4245 5150);
FORCEPROP 2 LAST PATH I137
J 0
(-4200 5200);
DISPLAY 1.021277 (-4200 5200);
DISPLAY INVISIBLE (-4200 5200);
FORCEPROP 1 LAST OFFPAGE TRUE
J 0
(-4290 5205);
DISPLAY 0.808511 (-4290 5205);
PAINT GREEN (-4290 5205);
DISPLAY INVISIBLE (-4290 5205);
FORCEPROP 1 LAST BODY_TYPE COMMENT
J 0
(-4290 5285);
DISPLAY 0.808511 (-4290 5285);
PAINT GREEN (-4290 5285);
DISPLAY INVISIBLE (-4290 5285);
FORCEPROP 2 LAST CDS_LIB cls
J 0
(-4300 5150);
PAINT MONO (-4300 5150);
DISPLAY INVISIBLE (-4300 5150);
FORCEPROP 1 LAST CDS_LMAN_SYM_OUTLINE -50,50,50,-50
J 0
(-4300 5150);
DISPLAY 0.468085 (-4300 5150);
PAINT GREEN (-4300 5150);
DISPLAY INVISIBLE (-4300 5150);
FORCEADD OFFPAGE_IN..2
R 2
(-11000 4950);
FORCEPROP 2 LAST $XR0 9D10> 
J 0
(-11183 4950);
DISPLAY 0.638298 (-11183 4950);
PAINT MONO (-11183 4950);
FORCEPROP 2 LAST $XR1 10J7> 
J 0
(-11363 4950);
DISPLAY 0.638298 (-11363 4950);
PAINT MONO (-11363 4950);
FORCEPROP 2 LAST PATH I189
J 0
(-10950 5050);
DISPLAY 1.021277 (-10950 5050);
DISPLAY INVISIBLE (-10950 5050);
FORCEPROP 1 LAST OFFPAGE TRUE
J 2
(-11010 5005);
DISPLAY 0.808511 (-11010 5005);
PAINT GREEN (-11010 5005);
DISPLAY INVISIBLE (-11010 5005);
FORCEPROP 2 LAST CDS_LIB cls
J 0
(-11000 4950);
DISPLAY INVISIBLE (-11000 4950);
FORCEPROP 1 LAST CDS_LMAN_SYM_OUTLINE -50,50,50,-50
J 2
(-11000 4950);
DISPLAY 0.468085 (-11000 4950);
PAINT GREEN (-11000 4950);
DISPLAY INVISIBLE (-11000 4950);
FORCEPROP 1 LAST BODY_TYPE COMMENT
J 2
(-11010 5085);
DISPLAY 0.808511 (-11010 5085);
PAINT GREEN (-11010 5085);
DISPLAY INVISIBLE (-11010 5085);
FORCEADD OFFPAGE_IN..2
R 2
(-11000 5050);
FORCEPROP 2 LAST $XR0 9D10> 
J 0
(-11183 5050);
DISPLAY 0.638298 (-11183 5050);
PAINT MONO (-11183 5050);
FORCEPROP 2 LAST $XR1 10J7> 
J 0
(-11363 5050);
DISPLAY 0.638298 (-11363 5050);
PAINT MONO (-11363 5050);
FORCEPROP 2 LAST PATH I190
J 0
(-10950 5150);
DISPLAY 1.021277 (-10950 5150);
DISPLAY INVISIBLE (-10950 5150);
FORCEPROP 1 LAST OFFPAGE TRUE
J 2
(-11010 5105);
DISPLAY 0.808511 (-11010 5105);
PAINT GREEN (-11010 5105);
DISPLAY INVISIBLE (-11010 5105);
FORCEPROP 1 LAST CDS_LMAN_SYM_OUTLINE -50,50,50,-50
J 2
(-11000 5050);
DISPLAY 0.468085 (-11000 5050);
PAINT GREEN (-11000 5050);
DISPLAY INVISIBLE (-11000 5050);
FORCEPROP 2 LAST CDS_LIB cls
J 0
(-11000 5050);
DISPLAY INVISIBLE (-11000 5050);
FORCEPROP 1 LAST BODY_TYPE COMMENT
J 2
(-11010 5185);
DISPLAY 0.808511 (-11010 5185);
PAINT GREEN (-11010 5185);
DISPLAY INVISIBLE (-11010 5185);
FORCEADD OFFPAGE_IN..2
R 2
(-11000 5250);
FORCEPROP 2 LAST $XR0 9D10> 
J 0
(-11183 5250);
DISPLAY 0.638298 (-11183 5250);
PAINT MONO (-11183 5250);
FORCEPROP 2 LAST $XR1 10K7> 
J 0
(-11363 5250);
DISPLAY 0.638298 (-11363 5250);
PAINT MONO (-11363 5250);
FORCEPROP 2 LAST PATH I191
J 0
(-10950 5350);
DISPLAY 1.021277 (-10950 5350);
DISPLAY INVISIBLE (-10950 5350);
FORCEPROP 1 LAST OFFPAGE TRUE
J 2
(-11010 5305);
DISPLAY 0.808511 (-11010 5305);
PAINT GREEN (-11010 5305);
DISPLAY INVISIBLE (-11010 5305);
FORCEPROP 2 LAST CDS_LIB cls
J 0
(-11000 5250);
DISPLAY INVISIBLE (-11000 5250);
FORCEPROP 1 LAST CDS_LMAN_SYM_OUTLINE -50,50,50,-50
J 2
(-11000 5250);
DISPLAY 0.468085 (-11000 5250);
PAINT GREEN (-11000 5250);
DISPLAY INVISIBLE (-11000 5250);
FORCEPROP 1 LAST BODY_TYPE COMMENT
J 2
(-11010 5385);
DISPLAY 0.808511 (-11010 5385);
PAINT GREEN (-11010 5385);
DISPLAY INVISIBLE (-11010 5385);
FORCEADD OFFPAGE_IN..2
(-4300 5550);
FORCEPROP 2 LAST $XR0 10H13> 
J 0
(-4245 5550);
DISPLAY 0.638298 (-4245 5550);
PAINT MONO (-4245 5550);
FORCEPROP 2 LAST PATH I193
J 2
(-4350 5650);
DISPLAY 1.021277 (-4350 5650);
DISPLAY INVISIBLE (-4350 5650);
FORCEPROP 1 LAST OFFPAGE TRUE
J 0
(-4290 5605);
DISPLAY 0.808511 (-4290 5605);
PAINT GREEN (-4290 5605);
DISPLAY INVISIBLE (-4290 5605);
FORCEPROP 1 LAST BODY_TYPE COMMENT
J 0
(-4290 5685);
DISPLAY 0.808511 (-4290 5685);
PAINT GREEN (-4290 5685);
DISPLAY INVISIBLE (-4290 5685);
FORCEPROP 1 LAST CDS_LMAN_SYM_OUTLINE -50,50,50,-50
J 0
(-4300 5550);
DISPLAY 0.468085 (-4300 5550);
PAINT GREEN (-4300 5550);
DISPLAY INVISIBLE (-4300 5550);
FORCEPROP 2 LAST CDS_LIB cls
J 2
(-4300 5550);
DISPLAY INVISIBLE (-4300 5550);
FORCEADD OFFPAGE_IN..2
(-4300 5450);
FORCEPROP 2 LAST $XR0 10H13> 
J 0
(-4245 5450);
DISPLAY 0.638298 (-4245 5450);
PAINT MONO (-4245 5450);
FORCEPROP 2 LAST PATH I194
J 0
(-4250 5550);
DISPLAY 1.021277 (-4250 5550);
DISPLAY INVISIBLE (-4250 5550);
FORCEPROP 1 LAST OFFPAGE TRUE
J 0
(-4290 5505);
DISPLAY 0.808511 (-4290 5505);
PAINT GREEN (-4290 5505);
DISPLAY INVISIBLE (-4290 5505);
FORCEPROP 1 LAST CDS_LMAN_SYM_OUTLINE -50,50,50,-50
J 0
(-4300 5450);
DISPLAY 0.468085 (-4300 5450);
PAINT GREEN (-4300 5450);
DISPLAY INVISIBLE (-4300 5450);
FORCEPROP 2 LAST CDS_LIB cls
J 0
(-4300 5450);
DISPLAY INVISIBLE (-4300 5450);
FORCEPROP 1 LAST BODY_TYPE COMMENT
J 0
(-4290 5585);
DISPLAY 0.808511 (-4290 5585);
PAINT GREEN (-4290 5585);
DISPLAY INVISIBLE (-4290 5585);
FORCEADD OFFPAGE_IN..2
(-4300 5350);
FORCEPROP 2 LAST $XR0 10H13> 
J 0
(-4245 5350);
DISPLAY 0.638298 (-4245 5350);
PAINT MONO (-4245 5350);
FORCEPROP 2 LAST PATH I195
J 0
(-4250 5450);
DISPLAY 1.021277 (-4250 5450);
DISPLAY INVISIBLE (-4250 5450);
FORCEPROP 1 LAST OFFPAGE TRUE
J 0
(-4290 5405);
DISPLAY 0.808511 (-4290 5405);
PAINT GREEN (-4290 5405);
DISPLAY INVISIBLE (-4290 5405);
FORCEPROP 2 LAST CDS_LIB cls
J 0
(-4300 5350);
DISPLAY INVISIBLE (-4300 5350);
FORCEPROP 1 LAST CDS_LMAN_SYM_OUTLINE -50,50,50,-50
J 0
(-4300 5350);
DISPLAY 0.468085 (-4300 5350);
PAINT GREEN (-4300 5350);
DISPLAY INVISIBLE (-4300 5350);
FORCEPROP 1 LAST BODY_TYPE COMMENT
J 0
(-4290 5485);
DISPLAY 0.808511 (-4290 5485);
PAINT GREEN (-4290 5485);
DISPLAY INVISIBLE (-4290 5485);
FORCEADD XC7A200T_2FBG484C_FBG484..1
(-8550 7950);
FORCEPROP 0 LASTPIN (-6650 5850) $PN M10
J 0
(-6640 5860);
DISPLAY 0.680851 (-6640 5860);
PAINT MONO (-6640 5860);
FORCEPROP 0 LASTPIN (-6650 5750) $PN L9
J 0
(-6640 5760);
DISPLAY 0.680851 (-6640 5760);
PAINT MONO (-6640 5760);
FORCEPROP 0 LASTPIN (-8650 5850) $PN L10
J 2
(-8660 5860);
DISPLAY 0.680851 (-8660 5860);
PAINT MONO (-8660 5860);
FORCEPROP 0 LASTPIN (-8650 5750) $PN M9
J 2
(-8660 5760);
DISPLAY 0.680851 (-8660 5760);
PAINT MONO (-8660 5760);
FORCEPROP 0 LASTPIN (-8650 4950) $PN T13
J 2
(-8660 4960);
DISPLAY 0.680851 (-8660 4960);
PAINT MONO (-8660 4960);
FORCEPROP 0 LASTPIN (-8650 5150) $PN U13
J 2
(-8660 5160);
DISPLAY 0.680851 (-8660 5160);
PAINT MONO (-8660 5160);
FORCEPROP 0 LASTPIN (-8650 5250) $PN R13
J 2
(-8660 5260);
DISPLAY 0.680851 (-8660 5260);
PAINT MONO (-8660 5260);
FORCEPROP 0 LASTPIN (-8650 5050) $PN V12
J 2
(-8660 5060);
DISPLAY 0.680851 (-8660 5060);
PAINT MONO (-8660 5060);
FORCEPROP 0 LASTPIN (-8650 4750) $PN N12
J 2
(-8660 4760);
DISPLAY 0.680851 (-8660 4760);
PAINT MONO (-8660 4760);
FORCEPROP 0 LASTPIN (-8650 6050) $PN F8
J 2
(-8660 6060);
DISPLAY 0.680851 (-8660 6060);
PAINT MONO (-8660 6060);
FORCEPROP 0 LASTPIN (-8650 6350) $PN F10
J 2
(-8660 6360);
DISPLAY 0.680851 (-8660 6360);
PAINT MONO (-8660 6360);
FORCEPROP 0 LASTPIN (-8650 6250) $PN E10
J 2
(-8660 6260);
DISPLAY 0.680851 (-8660 6260);
PAINT MONO (-8660 6260);
FORCEPROP 0 LASTPIN (-8650 6650) $PN F6
J 2
(-8660 6660);
DISPLAY 0.680851 (-8660 6660);
PAINT MONO (-8660 6660);
FORCEPROP 0 LASTPIN (-8650 6550) $PN E6
J 2
(-8660 6560);
DISPLAY 0.680851 (-8660 6560);
PAINT MONO (-8660 6560);
FORCEPROP 0 LASTPIN (-6650 6950) $PN D7
J 0
(-6640 6960);
DISPLAY 0.680851 (-6640 6960);
PAINT MONO (-6640 6960);
FORCEPROP 0 LASTPIN (-6650 7250) $PN B6
J 0
(-6640 7260);
DISPLAY 0.680851 (-6640 7260);
PAINT MONO (-6640 7260);
FORCEPROP 0 LASTPIN (-6650 7550) $PN D5
J 0
(-6640 7560);
DISPLAY 0.680851 (-6640 7560);
PAINT MONO (-6640 7560);
FORCEPROP 0 LASTPIN (-6650 7850) $PN B4
J 0
(-6640 7860);
DISPLAY 0.680851 (-6640 7860);
PAINT MONO (-6640 7860);
FORCEPROP 0 LASTPIN (-6650 6850) $PN C7
J 0
(-6640 6860);
DISPLAY 0.680851 (-6640 6860);
PAINT MONO (-6640 6860);
FORCEPROP 0 LASTPIN (-6650 7150) $PN A6
J 0
(-6640 7160);
DISPLAY 0.680851 (-6640 7160);
PAINT MONO (-6640 7160);
FORCEPROP 0 LASTPIN (-6650 7450) $PN C5
J 0
(-6640 7460);
DISPLAY 0.680851 (-6640 7460);
PAINT MONO (-6640 7460);
FORCEPROP 0 LASTPIN (-6650 7750) $PN A4
J 0
(-6640 7760);
DISPLAY 0.680851 (-6640 7760);
PAINT MONO (-6640 7760);
FORCEPROP 0 LASTPIN (-8650 6950) $PN D9
J 2
(-8660 6960);
DISPLAY 0.680851 (-8660 6960);
PAINT MONO (-8660 6960);
FORCEPROP 0 LASTPIN (-8650 7250) $PN B10
J 2
(-8660 7260);
DISPLAY 0.680851 (-8660 7260);
PAINT MONO (-8660 7260);
FORCEPROP 0 LASTPIN (-8650 7550) $PN D11
J 2
(-8660 7560);
DISPLAY 0.680851 (-8660 7560);
PAINT MONO (-8660 7560);
FORCEPROP 0 LASTPIN (-8650 7850) $PN B8
J 2
(-8660 7860);
DISPLAY 0.680851 (-8660 7860);
PAINT MONO (-8660 7860);
FORCEPROP 0 LASTPIN (-8650 6850) $PN C9
J 2
(-8660 6860);
DISPLAY 0.680851 (-8660 6860);
PAINT MONO (-8660 6860);
FORCEPROP 0 LASTPIN (-8650 7150) $PN A10
J 2
(-8660 7160);
DISPLAY 0.680851 (-8660 7160);
PAINT MONO (-8660 7160);
FORCEPROP 0 LASTPIN (-8650 7450) $PN C11
J 2
(-8660 7460);
DISPLAY 0.680851 (-8660 7460);
PAINT MONO (-8660 7460);
FORCEPROP 0 LASTPIN (-8650 7750) $PN A8
J 2
(-8660 7760);
DISPLAY 0.680851 (-8660 7760);
PAINT MONO (-8660 7760);
FORCEPROP 0 LASTPIN (-6650 5350) $PN U9
J 0
(-6640 5360);
DISPLAY 0.680851 (-6640 5360);
PAINT MONO (-6640 5360);
FORCEPROP 0 LASTPIN (-6650 5450) $PN U10
J 0
(-6640 5460);
DISPLAY 0.680851 (-6640 5460);
PAINT MONO (-6640 5460);
FORCEPROP 0 LASTPIN (-6650 5550) $PN U11
J 0
(-6640 5560);
DISPLAY 0.680851 (-6640 5560);
PAINT MONO (-6640 5560);
FORCEPROP 0 LASTPIN (-6650 4950) $PN U12
J 0
(-6640 4960);
DISPLAY 0.680851 (-6640 4960);
PAINT MONO (-6640 4960);
FORCEPROP 0 LASTPIN (-8650 5550) $PN N10
J 2
(-8660 5560);
DISPLAY 0.680851 (-8660 5560);
PAINT MONO (-8660 5560);
FORCEPROP 0 LASTPIN (-8650 5450) $PN N9
J 2
(-8660 5460);
DISPLAY 0.680851 (-8660 5460);
PAINT MONO (-8660 5460);
FORCEPROP 0 LASTPIN (-6650 5050) $PN G11
J 0
(-6640 5060);
DISPLAY 0.680851 (-6640 5060);
PAINT MONO (-6640 5060);
FORCEPROP 0 LASTPIN (-8650 4650) $PN U8
J 2
(-8660 4660);
DISPLAY 0.680851 (-8660 4660);
PAINT MONO (-8660 4660);
FORCEPROP 0 LASTPIN (-6650 5150) $PN L12
J 0
(-6640 5160);
DISPLAY 0.680851 (-6640 5160);
PAINT MONO (-6640 5160);
FORCEPROP 1 LAST $LOCATION U24
J 0
(-8500 8050);
DISPLAY 1.212766 (-8500 8050);
PAINT GREEN (-8500 8050);
FORCEPROP 1 LAST CLS_PN G240-10069-01
J 0
(-8500 8150);
DISPLAY 1.212766 (-8500 8150);
PAINT GREEN (-8500 8150);
FORCEPROP 0 LAST CDS_SEC 1
J 0
(-8500 8350);
DISPLAY 1.021277 (-8500 8350);
DISPLAY INVISIBLE (-8500 8350);
FORCEPROP 0 LAST $SEC 1
J 0
(-8500 8350);
DISPLAY 0.680851 (-8500 8350);
PAINT MONO (-8500 8350);
DISPLAY INVISIBLE (-8500 8350);
FORCEPROP 0 LAST CDS_LOCATION U24
J 0
(-8500 8350);
DISPLAY 1.021277 (-8500 8350);
DISPLAY INVISIBLE (-8500 8350);
FORCEPROP 1 LAST PATH I232
J 0
(-8500 8000);
DISPLAY 1.212766 (-8500 8000);
PAINT GREEN (-8500 8000);
DISPLAY INVISIBLE (-8500 8000);
FORCEPROP 2 LAST CDS_LIB pld
J 0
(-8550 7950);
DISPLAY INVISIBLE (-8550 7950);
FORCEPROP 1 LAST CDS_LMAN_SYM_OUTLINE 0,0,1800,-3400
J 0
(-8550 7950);
DISPLAY 0.468085 (-8550 7950);
PAINT GREEN (-8550 7950);
DISPLAY INVISIBLE (-8550 7950);
FORCEADD VCC..1
(-10700 5950);
FORCEPROP 3 LASTPIN (-10650 5900) SIG_NAME FPGA_MGTAVTT\g
J 0
(-10640 5910);
DISPLAY 0.659574 (-10640 5910);
PAINT MONO (-10640 5910);
DISPLAY INVISIBLE (-10640 5910);
FORCEPROP 1 LAST HDL_POWER FPGA_MGTAVTT
J 1
(-10645 6005);
DISPLAY 0.808511 (-10645 6005);
PAINT GREEN (-10645 6005);
FORCEPROP 0 LAST VOLTAGE 1.2
J 0
(-10850 6050);
DISPLAY 0.808511 (-10850 6050);
DISPLAY BOTH (-10850 6050);
FORCEPROP 1 LAST PATH I243
J 0
(-10665 6040);
DISPLAY 0.808511 (-10665 6040);
PAINT GREEN (-10665 6040);
DISPLAY INVISIBLE (-10665 6040);
FORCEPROP 1 LAST BODY_TYPE PLUMBING
J 0
(-10745 5907);
DISPLAY 0.340426 (-10745 5907);
PAINT GREEN (-10745 5907);
DISPLAY INVISIBLE (-10745 5907);
FORCEPROP 1 LAST CDS_LMAN_SYM_OUTLINE -250,250,250,-250
J 0
(-10700 5950);
DISPLAY 0.468085 (-10700 5950);
PAINT GREEN (-10700 5950);
DISPLAY INVISIBLE (-10700 5950);
FORCEPROP 2 LAST CDS_LIB cls
J 0
(-10700 5950);
DISPLAY INVISIBLE (-10700 5950);
FORCEADD OFFPAGE_OUT..1
(-4250 7550);
FORCEPROP 2 LAST $XR0 9F11< 
J 0
(-4195 7550);
DISPLAY 0.638298 (-4195 7550);
PAINT MONO (-4195 7550);
FORCEPROP 2 LAST PATH I260
J 0
(-4200 7650);
DISPLAY 1.021277 (-4200 7650);
DISPLAY INVISIBLE (-4200 7650);
FORCEPROP 1 LAST OFFPAGE TRUE
J 0
(-4240 7605);
DISPLAY 0.808511 (-4240 7605);
PAINT GREEN (-4240 7605);
DISPLAY INVISIBLE (-4240 7605);
FORCEPROP 2 LAST CDS_LIB cls
J 0
(-4250 7550);
DISPLAY INVISIBLE (-4250 7550);
FORCEPROP 1 LAST CDS_LMAN_SYM_OUTLINE -50,50,50,-50
J 0
(-4250 7550);
DISPLAY 0.468085 (-4250 7550);
PAINT GREEN (-4250 7550);
DISPLAY INVISIBLE (-4250 7550);
FORCEPROP 1 LAST BODY_TYPE COMMENT
J 0
(-4240 7685);
DISPLAY 0.808511 (-4240 7685);
PAINT GREEN (-4240 7685);
DISPLAY INVISIBLE (-4240 7685);
FORCEADD OFFPAGE_OUT..1
(-4250 7450);
FORCEPROP 2 LAST $XR0 9F11< 
J 0
(-4195 7450);
DISPLAY 0.638298 (-4195 7450);
PAINT MONO (-4195 7450);
FORCEPROP 2 LAST PATH I261
J 0
(-4200 7550);
DISPLAY 1.021277 (-4200 7550);
DISPLAY INVISIBLE (-4200 7550);
FORCEPROP 1 LAST OFFPAGE TRUE
J 0
(-4240 7505);
DISPLAY 0.808511 (-4240 7505);
PAINT GREEN (-4240 7505);
DISPLAY INVISIBLE (-4240 7505);
FORCEPROP 2 LAST CDS_LIB cls
J 0
(-4250 7450);
DISPLAY INVISIBLE (-4250 7450);
FORCEPROP 1 LAST CDS_LMAN_SYM_OUTLINE -50,50,50,-50
J 0
(-4250 7450);
DISPLAY 0.468085 (-4250 7450);
PAINT GREEN (-4250 7450);
DISPLAY INVISIBLE (-4250 7450);
FORCEPROP 1 LAST BODY_TYPE COMMENT
J 0
(-4240 7585);
DISPLAY 0.808511 (-4240 7585);
PAINT GREEN (-4240 7585);
DISPLAY INVISIBLE (-4240 7585);
FORCEADD OFFPAGE_IN..1
(-11450 6650);
FORCEPROP 2 LAST $XR0 15H12> 
J 0
(-11664 6650);
DISPLAY 0.638298 (-11664 6650);
PAINT MONO (-11664 6650);
FORCEPROP 2 LAST PATH I267
J 0
(-11400 6750);
DISPLAY 1.021277 (-11400 6750);
DISPLAY INVISIBLE (-11400 6750);
FORCEPROP 1 LAST OFFPAGE TRUE
J 0
(-11440 6705);
DISPLAY 0.808511 (-11440 6705);
PAINT GREEN (-11440 6705);
DISPLAY INVISIBLE (-11440 6705);
FORCEPROP 2 LAST CDS_LIB cls
J 0
(-11450 6650);
DISPLAY INVISIBLE (-11450 6650);
FORCEPROP 1 LAST CDS_LMAN_SYM_OUTLINE -50,50,50,-50
J 0
(-11450 6650);
DISPLAY 0.468085 (-11450 6650);
PAINT GREEN (-11450 6650);
DISPLAY INVISIBLE (-11450 6650);
FORCEPROP 1 LAST BODY_TYPE COMMENT
J 0
(-11440 6785);
DISPLAY 0.808511 (-11440 6785);
PAINT GREEN (-11440 6785);
DISPLAY INVISIBLE (-11440 6785);
FORCEADD OFFPAGE_IN..1
(-11450 6550);
FORCEPROP 2 LAST $XR0 15H12> 
J 0
(-11664 6550);
DISPLAY 0.638298 (-11664 6550);
PAINT MONO (-11664 6550);
FORCEPROP 2 LAST PATH I268
J 0
(-11400 6650);
DISPLAY 1.021277 (-11400 6650);
DISPLAY INVISIBLE (-11400 6650);
FORCEPROP 1 LAST OFFPAGE TRUE
J 0
(-11440 6605);
DISPLAY 0.808511 (-11440 6605);
PAINT GREEN (-11440 6605);
DISPLAY INVISIBLE (-11440 6605);
FORCEPROP 1 LAST BODY_TYPE COMMENT
J 0
(-11440 6685);
DISPLAY 0.808511 (-11440 6685);
PAINT GREEN (-11440 6685);
DISPLAY INVISIBLE (-11440 6685);
FORCEPROP 1 LAST CDS_LMAN_SYM_OUTLINE -50,50,50,-50
J 0
(-11450 6550);
DISPLAY 0.468085 (-11450 6550);
PAINT GREEN (-11450 6550);
DISPLAY INVISIBLE (-11450 6550);
FORCEPROP 2 LAST CDS_LIB cls
J 0
(-11450 6550);
DISPLAY INVISIBLE (-11450 6550);
FORCEADD OFFPAGE_IN..1
(-11450 7750);
FORCEPROP 2 LAST $XR0 9E3> 
J 0
(-11602 7750);
DISPLAY 0.638298 (-11602 7750);
PAINT MONO (-11602 7750);
FORCEPROP 2 LAST PATH I293
J 0
(-11600 7800);
DISPLAY 1.021277 (-11600 7800);
DISPLAY INVISIBLE (-11600 7800);
FORCEPROP 1 LAST OFFPAGE TRUE
J 0
(-11440 7805);
DISPLAY 0.808511 (-11440 7805);
PAINT GREEN (-11440 7805);
DISPLAY INVISIBLE (-11440 7805);
FORCEPROP 2 LAST CDS_LIB cls
J 0
(-11450 7750);
DISPLAY INVISIBLE (-11450 7750);
FORCEPROP 1 LAST CDS_LMAN_SYM_OUTLINE -50,50,50,-50
J 0
(-11450 7750);
DISPLAY 0.468085 (-11450 7750);
PAINT GREEN (-11450 7750);
DISPLAY INVISIBLE (-11450 7750);
FORCEPROP 1 LAST BODY_TYPE COMMENT
J 0
(-11440 7885);
DISPLAY 0.808511 (-11440 7885);
PAINT GREEN (-11440 7885);
DISPLAY INVISIBLE (-11440 7885);
FORCEADD OFFPAGE_IN..1
(-11450 7850);
FORCEPROP 2 LAST $XR0 9E3> 
J 0
(-11602 7850);
DISPLAY 0.638298 (-11602 7850);
PAINT MONO (-11602 7850);
FORCEPROP 2 LAST PATH I294
J 0
(-11600 7900);
DISPLAY 1.021277 (-11600 7900);
DISPLAY INVISIBLE (-11600 7900);
FORCEPROP 1 LAST OFFPAGE TRUE
J 0
(-11440 7905);
DISPLAY 0.808511 (-11440 7905);
PAINT GREEN (-11440 7905);
DISPLAY INVISIBLE (-11440 7905);
FORCEPROP 2 LAST CDS_LIB cls
J 0
(-11450 7850);
DISPLAY INVISIBLE (-11450 7850);
FORCEPROP 1 LAST CDS_LMAN_SYM_OUTLINE -50,50,50,-50
J 0
(-11450 7850);
DISPLAY 0.468085 (-11450 7850);
PAINT GREEN (-11450 7850);
DISPLAY INVISIBLE (-11450 7850);
FORCEPROP 1 LAST BODY_TYPE COMMENT
J 0
(-11440 7985);
DISPLAY 0.808511 (-11440 7985);
PAINT GREEN (-11440 7985);
DISPLAY INVISIBLE (-11440 7985);
FORCEADD OFFPAGE_IN..1
(-11450 7550);
FORCEPROP 2 LAST $XR0 9F3> 
J 0
(-11602 7550);
DISPLAY 0.638298 (-11602 7550);
PAINT MONO (-11602 7550);
FORCEPROP 2 LAST PATH I295
J 0
(-11600 7600);
DISPLAY 1.021277 (-11600 7600);
DISPLAY INVISIBLE (-11600 7600);
FORCEPROP 1 LAST OFFPAGE TRUE
J 0
(-11440 7605);
DISPLAY 0.808511 (-11440 7605);
PAINT GREEN (-11440 7605);
DISPLAY INVISIBLE (-11440 7605);
FORCEPROP 2 LAST CDS_LIB cls
J 0
(-11450 7550);
DISPLAY INVISIBLE (-11450 7550);
FORCEPROP 1 LAST CDS_LMAN_SYM_OUTLINE -50,50,50,-50
J 0
(-11450 7550);
DISPLAY 0.468085 (-11450 7550);
PAINT GREEN (-11450 7550);
DISPLAY INVISIBLE (-11450 7550);
FORCEPROP 1 LAST BODY_TYPE COMMENT
J 0
(-11440 7685);
DISPLAY 0.808511 (-11440 7685);
PAINT GREEN (-11440 7685);
DISPLAY INVISIBLE (-11440 7685);
FORCEADD OFFPAGE_IN..1
(-11450 7450);
FORCEPROP 2 LAST $XR0 9F3> 
J 0
(-11602 7450);
DISPLAY 0.638298 (-11602 7450);
PAINT MONO (-11602 7450);
FORCEPROP 2 LAST PATH I296
J 0
(-11600 7500);
DISPLAY 1.021277 (-11600 7500);
DISPLAY INVISIBLE (-11600 7500);
FORCEPROP 1 LAST OFFPAGE TRUE
J 0
(-11440 7505);
DISPLAY 0.808511 (-11440 7505);
PAINT GREEN (-11440 7505);
DISPLAY INVISIBLE (-11440 7505);
FORCEPROP 2 LAST CDS_LIB cls
J 0
(-11450 7450);
DISPLAY INVISIBLE (-11450 7450);
FORCEPROP 1 LAST CDS_LMAN_SYM_OUTLINE -50,50,50,-50
J 0
(-11450 7450);
DISPLAY 0.468085 (-11450 7450);
PAINT GREEN (-11450 7450);
DISPLAY INVISIBLE (-11450 7450);
FORCEPROP 1 LAST BODY_TYPE COMMENT
J 0
(-11440 7585);
DISPLAY 0.808511 (-11440 7585);
PAINT GREEN (-11440 7585);
DISPLAY INVISIBLE (-11440 7585);
FORCEADD OFFPAGE_IN..1
(-11450 7150);
FORCEPROP 2 LAST $XR0 9F3> 
J 0
(-11602 7150);
DISPLAY 0.638298 (-11602 7150);
PAINT MONO (-11602 7150);
FORCEPROP 2 LAST PATH I297
J 0
(-11600 7200);
DISPLAY 1.021277 (-11600 7200);
DISPLAY INVISIBLE (-11600 7200);
FORCEPROP 1 LAST OFFPAGE TRUE
J 0
(-11440 7205);
DISPLAY 0.808511 (-11440 7205);
PAINT GREEN (-11440 7205);
DISPLAY INVISIBLE (-11440 7205);
FORCEPROP 1 LAST BODY_TYPE COMMENT
J 0
(-11440 7285);
DISPLAY 0.808511 (-11440 7285);
PAINT GREEN (-11440 7285);
DISPLAY INVISIBLE (-11440 7285);
FORCEPROP 1 LAST CDS_LMAN_SYM_OUTLINE -50,50,50,-50
J 0
(-11450 7150);
DISPLAY 0.468085 (-11450 7150);
PAINT GREEN (-11450 7150);
DISPLAY INVISIBLE (-11450 7150);
FORCEPROP 2 LAST CDS_LIB cls
J 0
(-11450 7150);
DISPLAY INVISIBLE (-11450 7150);
FORCEADD OFFPAGE_IN..1
(-11450 7250);
FORCEPROP 2 LAST $XR0 9F3> 
J 0
(-11602 7250);
DISPLAY 0.638298 (-11602 7250);
PAINT MONO (-11602 7250);
FORCEPROP 2 LAST PATH I298
J 0
(-11600 7300);
DISPLAY 1.021277 (-11600 7300);
DISPLAY INVISIBLE (-11600 7300);
FORCEPROP 1 LAST OFFPAGE TRUE
J 0
(-11440 7305);
DISPLAY 0.808511 (-11440 7305);
PAINT GREEN (-11440 7305);
DISPLAY INVISIBLE (-11440 7305);
FORCEPROP 1 LAST BODY_TYPE COMMENT
J 0
(-11440 7385);
DISPLAY 0.808511 (-11440 7385);
PAINT GREEN (-11440 7385);
DISPLAY INVISIBLE (-11440 7385);
FORCEPROP 1 LAST CDS_LMAN_SYM_OUTLINE -50,50,50,-50
J 0
(-11450 7250);
DISPLAY 0.468085 (-11450 7250);
PAINT GREEN (-11450 7250);
DISPLAY INVISIBLE (-11450 7250);
FORCEPROP 2 LAST CDS_LIB cls
J 0
(-11450 7250);
DISPLAY INVISIBLE (-11450 7250);
FORCEADD OFFPAGE_IN..1
(-11450 6850);
FORCEPROP 2 LAST $XR0 9G3> 
J 0
(-11602 6850);
DISPLAY 0.638298 (-11602 6850);
PAINT MONO (-11602 6850);
FORCEPROP 2 LAST PATH I299
J 0
(-11600 6900);
DISPLAY 1.021277 (-11600 6900);
DISPLAY INVISIBLE (-11600 6900);
FORCEPROP 1 LAST OFFPAGE TRUE
J 0
(-11440 6905);
DISPLAY 0.808511 (-11440 6905);
PAINT GREEN (-11440 6905);
DISPLAY INVISIBLE (-11440 6905);
FORCEPROP 1 LAST BODY_TYPE COMMENT
J 0
(-11440 6985);
DISPLAY 0.808511 (-11440 6985);
PAINT GREEN (-11440 6985);
DISPLAY INVISIBLE (-11440 6985);
FORCEPROP 1 LAST CDS_LMAN_SYM_OUTLINE -50,50,50,-50
J 0
(-11450 6850);
DISPLAY 0.468085 (-11450 6850);
PAINT GREEN (-11450 6850);
DISPLAY INVISIBLE (-11450 6850);
FORCEPROP 2 LAST CDS_LIB cls
J 0
(-11450 6850);
DISPLAY INVISIBLE (-11450 6850);
FORCEADD OFFPAGE_IN..1
(-11450 6950);
FORCEPROP 2 LAST $XR0 9F3> 
J 0
(-11602 6950);
DISPLAY 0.638298 (-11602 6950);
PAINT MONO (-11602 6950);
FORCEPROP 2 LAST PATH I300
J 0
(-11600 7000);
DISPLAY 1.021277 (-11600 7000);
DISPLAY INVISIBLE (-11600 7000);
FORCEPROP 1 LAST OFFPAGE TRUE
J 0
(-11440 7005);
DISPLAY 0.808511 (-11440 7005);
PAINT GREEN (-11440 7005);
DISPLAY INVISIBLE (-11440 7005);
FORCEPROP 1 LAST BODY_TYPE COMMENT
J 0
(-11440 7085);
DISPLAY 0.808511 (-11440 7085);
PAINT GREEN (-11440 7085);
DISPLAY INVISIBLE (-11440 7085);
FORCEPROP 1 LAST CDS_LMAN_SYM_OUTLINE -50,50,50,-50
J 0
(-11450 6950);
DISPLAY 0.468085 (-11450 6950);
PAINT GREEN (-11450 6950);
DISPLAY INVISIBLE (-11450 6950);
FORCEPROP 2 LAST CDS_LIB cls
J 0
(-11450 6950);
DISPLAY INVISIBLE (-11450 6950);
FORCEADD OFFPAGE_OUT..1
(-4250 7850);
FORCEPROP 2 LAST $XR0 9E11< 
J 0
(-4195 7850);
DISPLAY 0.638298 (-4195 7850);
PAINT MONO (-4195 7850);
FORCEPROP 2 LAST PATH I302
J 0
(-4150 7900);
DISPLAY 1.021277 (-4150 7900);
DISPLAY INVISIBLE (-4150 7900);
FORCEPROP 1 LAST OFFPAGE TRUE
J 0
(-4240 7905);
DISPLAY 0.808511 (-4240 7905);
PAINT GREEN (-4240 7905);
DISPLAY INVISIBLE (-4240 7905);
FORCEPROP 2 LAST CDS_LIB cls
J 0
(-4250 7850);
DISPLAY INVISIBLE (-4250 7850);
FORCEPROP 1 LAST CDS_LMAN_SYM_OUTLINE -50,50,50,-50
J 0
(-4250 7850);
DISPLAY 0.468085 (-4250 7850);
PAINT GREEN (-4250 7850);
DISPLAY INVISIBLE (-4250 7850);
FORCEPROP 1 LAST BODY_TYPE COMMENT
J 0
(-4240 7985);
DISPLAY 0.808511 (-4240 7985);
PAINT GREEN (-4240 7985);
DISPLAY INVISIBLE (-4240 7985);
FORCEADD OFFPAGE_OUT..1
(-4250 7750);
FORCEPROP 2 LAST $XR0 9E11< 
J 0
(-4195 7750);
DISPLAY 0.638298 (-4195 7750);
PAINT MONO (-4195 7750);
FORCEPROP 2 LAST PATH I303
J 0
(-4150 7800);
DISPLAY 1.021277 (-4150 7800);
DISPLAY INVISIBLE (-4150 7800);
FORCEPROP 1 LAST OFFPAGE TRUE
J 0
(-4240 7805);
DISPLAY 0.808511 (-4240 7805);
PAINT GREEN (-4240 7805);
DISPLAY INVISIBLE (-4240 7805);
FORCEPROP 2 LAST CDS_LIB cls
J 0
(-4250 7750);
DISPLAY INVISIBLE (-4250 7750);
FORCEPROP 1 LAST CDS_LMAN_SYM_OUTLINE -50,50,50,-50
J 0
(-4250 7750);
DISPLAY 0.468085 (-4250 7750);
PAINT GREEN (-4250 7750);
DISPLAY INVISIBLE (-4250 7750);
FORCEPROP 1 LAST BODY_TYPE COMMENT
J 0
(-4240 7885);
DISPLAY 0.808511 (-4240 7885);
PAINT GREEN (-4240 7885);
DISPLAY INVISIBLE (-4240 7885);
FORCEADD OFFPAGE_OUT..1
(-4250 7250);
FORCEPROP 2 LAST $XR0 9F11< 
J 0
(-4195 7250);
DISPLAY 0.638298 (-4195 7250);
PAINT MONO (-4195 7250);
FORCEPROP 2 LAST PATH I305
J 0
(-4150 7300);
DISPLAY 1.021277 (-4150 7300);
DISPLAY INVISIBLE (-4150 7300);
FORCEPROP 1 LAST OFFPAGE TRUE
J 0
(-4240 7305);
DISPLAY 0.808511 (-4240 7305);
PAINT GREEN (-4240 7305);
DISPLAY INVISIBLE (-4240 7305);
FORCEPROP 2 LAST CDS_LIB cls
J 0
(-4250 7250);
DISPLAY INVISIBLE (-4250 7250);
FORCEPROP 1 LAST CDS_LMAN_SYM_OUTLINE -50,50,50,-50
J 0
(-4250 7250);
DISPLAY 0.468085 (-4250 7250);
PAINT GREEN (-4250 7250);
DISPLAY INVISIBLE (-4250 7250);
FORCEPROP 1 LAST BODY_TYPE COMMENT
J 0
(-4240 7385);
DISPLAY 0.808511 (-4240 7385);
PAINT GREEN (-4240 7385);
DISPLAY INVISIBLE (-4240 7385);
FORCEADD OFFPAGE_OUT..1
(-4250 7150);
FORCEPROP 2 LAST $XR0 9F11< 
J 0
(-4195 7150);
DISPLAY 0.638298 (-4195 7150);
PAINT MONO (-4195 7150);
FORCEPROP 2 LAST PATH I306
J 0
(-4150 7200);
DISPLAY 1.021277 (-4150 7200);
DISPLAY INVISIBLE (-4150 7200);
FORCEPROP 1 LAST OFFPAGE TRUE
J 0
(-4240 7205);
DISPLAY 0.808511 (-4240 7205);
PAINT GREEN (-4240 7205);
DISPLAY INVISIBLE (-4240 7205);
FORCEPROP 2 LAST CDS_LIB cls
J 0
(-4250 7150);
DISPLAY INVISIBLE (-4250 7150);
FORCEPROP 1 LAST CDS_LMAN_SYM_OUTLINE -50,50,50,-50
J 0
(-4250 7150);
DISPLAY 0.468085 (-4250 7150);
PAINT GREEN (-4250 7150);
DISPLAY INVISIBLE (-4250 7150);
FORCEPROP 1 LAST BODY_TYPE COMMENT
J 0
(-4240 7285);
DISPLAY 0.808511 (-4240 7285);
PAINT GREEN (-4240 7285);
DISPLAY INVISIBLE (-4240 7285);
FORCEADD OFFPAGE_OUT..1
(-4250 6950);
FORCEPROP 2 LAST $XR0 9G11< 
J 0
(-4195 6950);
DISPLAY 0.638298 (-4195 6950);
PAINT MONO (-4195 6950);
FORCEPROP 2 LAST PATH I307
J 0
(-4150 7000);
DISPLAY 1.021277 (-4150 7000);
DISPLAY INVISIBLE (-4150 7000);
FORCEPROP 1 LAST OFFPAGE TRUE
J 0
(-4240 7005);
DISPLAY 0.808511 (-4240 7005);
PAINT GREEN (-4240 7005);
DISPLAY INVISIBLE (-4240 7005);
FORCEPROP 2 LAST CDS_LIB cls
J 0
(-4250 6950);
DISPLAY INVISIBLE (-4250 6950);
FORCEPROP 1 LAST CDS_LMAN_SYM_OUTLINE -50,50,50,-50
J 0
(-4250 6950);
DISPLAY 0.468085 (-4250 6950);
PAINT GREEN (-4250 6950);
DISPLAY INVISIBLE (-4250 6950);
FORCEPROP 1 LAST BODY_TYPE COMMENT
J 0
(-4240 7085);
DISPLAY 0.808511 (-4240 7085);
PAINT GREEN (-4240 7085);
DISPLAY INVISIBLE (-4240 7085);
FORCEADD OFFPAGE_OUT..1
(-4250 6850);
FORCEPROP 2 LAST $XR0 9G11< 
J 0
(-4195 6850);
DISPLAY 0.638298 (-4195 6850);
PAINT MONO (-4195 6850);
FORCEPROP 2 LAST PATH I308
J 0
(-4150 6900);
DISPLAY 1.021277 (-4150 6900);
DISPLAY INVISIBLE (-4150 6900);
FORCEPROP 1 LAST OFFPAGE TRUE
J 0
(-4240 6905);
DISPLAY 0.808511 (-4240 6905);
PAINT GREEN (-4240 6905);
DISPLAY INVISIBLE (-4240 6905);
FORCEPROP 2 LAST CDS_LIB cls
J 0
(-4250 6850);
DISPLAY INVISIBLE (-4250 6850);
FORCEPROP 1 LAST CDS_LMAN_SYM_OUTLINE -50,50,50,-50
J 0
(-4250 6850);
DISPLAY 0.468085 (-4250 6850);
PAINT GREEN (-4250 6850);
DISPLAY INVISIBLE (-4250 6850);
FORCEPROP 1 LAST BODY_TYPE COMMENT
J 0
(-4240 6985);
DISPLAY 0.808511 (-4240 6985);
PAINT GREEN (-4240 6985);
DISPLAY INVISIBLE (-4240 6985);
FORCEADD RESISTOR..1
(-10350 4650);
FORCEPROP 0 LASTPIN (-10200 4650) $PN 2
J 0
(-10190 4660);
DISPLAY 0.680851 (-10190 4660);
PAINT MONO (-10190 4660);
FORCEPROP 0 LASTPIN (-10450 4650) $PN 1
J 2
(-10460 4660);
DISPLAY 0.680851 (-10460 4660);
PAINT MONO (-10460 4660);
FORCEPROP 1 LAST $LOCATION R194
J 2
(-10550 4650);
DISPLAY 1.212766 (-10550 4650);
PAINT GREEN (-10550 4650);
FORCEPROP 0 LAST PACKAGE 0402
J 0
(-10400 4600);
DISPLAY 0.638298 (-10400 4600);
FORCEPROP 1 LAST VALUE 4.7KOHM
J 0
(-10111 4655);
DISPLAY 1.212766 (-10111 4655);
PAINT GREEN (-10111 4655);
FORCEPROP 0 LAST CDS_SEC 1
J 0
(-10100 4750);
DISPLAY 1.021277 (-10100 4750);
DISPLAY INVISIBLE (-10100 4750);
FORCEPROP 0 LAST $SEC 1
J 0
(-10100 4750);
DISPLAY 0.680851 (-10100 4750);
PAINT MONO (-10100 4750);
DISPLAY INVISIBLE (-10100 4750);
FORCEPROP 0 LAST CDS_LOCATION R194
J 0
(-10100 4750);
DISPLAY 1.021277 (-10100 4750);
DISPLAY INVISIBLE (-10100 4750);
FORCEPROP 1 LAST PATH I329
J 0
(-10547 4755);
DISPLAY 1.212766 (-10547 4755);
PAINT GREEN (-10547 4755);
DISPLAY INVISIBLE (-10547 4755);
FORCEPROP 1 LAST TOLERANCE 1%
J 0
(-10547 4905);
DISPLAY 1.212766 (-10547 4905);
PAINT GREEN (-10547 4905);
DISPLAY INVISIBLE (-10547 4905);
FORCEPROP 2 LAST CDS_LIB passive
J 0
(-10350 4650);
DISPLAY INVISIBLE (-10350 4650);
FORCEPROP 1 LAST CDS_LMAN_SYM_OUTLINE -50,50,100,-50
J 0
(-10350 4650);
DISPLAY 0.468085 (-10350 4650);
PAINT GREEN (-10350 4650);
DISPLAY INVISIBLE (-10350 4650);
FORCEPROP 1 LAST CLS_PN G155-14701-01
J 0
(-10486 4850);
DISPLAY 1.212766 (-10486 4850);
PAINT GREEN (-10486 4850);
DISPLAY INVISIBLE (-10486 4850);
FORCEADD RESISTOR..1
(-10350 4750);
FORCEPROP 0 LASTPIN (-10200 4750) $PN 2
J 0
(-10190 4760);
DISPLAY 0.680851 (-10190 4760);
PAINT MONO (-10190 4760);
FORCEPROP 0 LASTPIN (-10450 4750) $PN 1
J 2
(-10460 4760);
DISPLAY 0.680851 (-10460 4760);
PAINT MONO (-10460 4760);
FORCEPROP 1 LAST $LOCATION R193
J 2
(-10550 4750);
DISPLAY 1.212766 (-10550 4750);
PAINT GREEN (-10550 4750);
FORCEPROP 1 LAST VALUE 4.7KOHM
J 0
(-10111 4755);
DISPLAY 1.212766 (-10111 4755);
PAINT GREEN (-10111 4755);
FORCEPROP 0 LAST PACKAGE 0402
J 0
(-10400 4700);
DISPLAY 0.638298 (-10400 4700);
FORCEPROP 0 LAST CDS_SEC 1
J 0
(-10100 4850);
DISPLAY 1.021277 (-10100 4850);
DISPLAY INVISIBLE (-10100 4850);
FORCEPROP 0 LAST $SEC 1
J 0
(-10100 4850);
DISPLAY 0.680851 (-10100 4850);
PAINT MONO (-10100 4850);
DISPLAY INVISIBLE (-10100 4850);
FORCEPROP 0 LAST CDS_LOCATION R193
J 0
(-10100 4850);
DISPLAY 1.021277 (-10100 4850);
DISPLAY INVISIBLE (-10100 4850);
FORCEPROP 1 LAST PATH I330
J 0
(-10547 4855);
DISPLAY 1.212766 (-10547 4855);
PAINT GREEN (-10547 4855);
DISPLAY INVISIBLE (-10547 4855);
FORCEPROP 1 LAST TOLERANCE 1%
J 0
(-10547 5005);
DISPLAY 1.212766 (-10547 5005);
PAINT GREEN (-10547 5005);
DISPLAY INVISIBLE (-10547 5005);
FORCEPROP 1 LAST CLS_PN G155-14701-01
J 0
(-10486 4950);
DISPLAY 1.212766 (-10486 4950);
PAINT GREEN (-10486 4950);
DISPLAY INVISIBLE (-10486 4950);
FORCEPROP 2 LAST CDS_LIB passive
J 0
(-10350 4750);
DISPLAY INVISIBLE (-10350 4750);
FORCEPROP 1 LAST CDS_LMAN_SYM_OUTLINE -50,50,100,-50
J 0
(-10350 4750);
DISPLAY 0.468085 (-10350 4750);
PAINT GREEN (-10350 4750);
DISPLAY INVISIBLE (-10350 4750);
FORCEADD RESISTOR..1
(-9950 5150);
FORCEPROP 0 LASTPIN (-9800 5150) $PN 2
J 0
(-9790 5160);
DISPLAY 0.680851 (-9790 5160);
PAINT MONO (-9790 5160);
FORCEPROP 0 LASTPIN (-10050 5150) $PN 1
J 2
(-10060 5160);
DISPLAY 0.680851 (-10060 5160);
PAINT MONO (-10060 5160);
FORCEPROP 1 LAST $LOCATION R195
J 2
(-10100 5150);
DISPLAY 1.212766 (-10100 5150);
PAINT GREEN (-10100 5150);
FORCEPROP 0 LAST PACKAGE 0402
J 0
(-10000 5200);
DISPLAY 0.638298 (-10000 5200);
FORCEPROP 1 LAST VALUE 33OHM
J 0
(-9711 5155);
DISPLAY 1.212766 (-9711 5155);
PAINT GREEN (-9711 5155);
FORCEPROP 0 LAST CDS_SEC 1
J 0
(-9700 5250);
DISPLAY 1.021277 (-9700 5250);
DISPLAY INVISIBLE (-9700 5250);
FORCEPROP 0 LAST $SEC 1
J 0
(-9700 5250);
DISPLAY 0.680851 (-9700 5250);
PAINT MONO (-9700 5250);
DISPLAY INVISIBLE (-9700 5250);
FORCEPROP 0 LAST CDS_LOCATION R195
J 0
(-9700 5250);
DISPLAY 1.021277 (-9700 5250);
DISPLAY INVISIBLE (-9700 5250);
FORCEPROP 1 LAST PATH I331
J 0
(-10147 5255);
DISPLAY 1.212766 (-10147 5255);
PAINT GREEN (-10147 5255);
DISPLAY INVISIBLE (-10147 5255);
FORCEPROP 1 LAST TOLERANCE 1%
J 0
(-10147 5405);
DISPLAY 1.212766 (-10147 5405);
PAINT GREEN (-10147 5405);
DISPLAY INVISIBLE (-10147 5405);
FORCEPROP 1 LAST CLS_PN G155-133R0-01
J 0
(-10086 5350);
DISPLAY 1.212766 (-10086 5350);
PAINT GREEN (-10086 5350);
DISPLAY INVISIBLE (-10086 5350);
FORCEPROP 2 LAST CDS_LIB passive
J 0
(-9950 5150);
DISPLAY INVISIBLE (-9950 5150);
FORCEPROP 1 LAST CDS_LMAN_SYM_OUTLINE -50,50,100,-50
J 0
(-9950 5150);
DISPLAY 0.468085 (-9950 5150);
PAINT GREEN (-9950 5150);
DISPLAY INVISIBLE (-9950 5150);
FORCEADD RESISTOR..1
(-10150 5800);
FORCEPROP 0 LASTPIN (-10000 5800) $PN 2
J 0
(-9990 5810);
DISPLAY 0.680851 (-9990 5810);
PAINT MONO (-9990 5810);
FORCEPROP 0 LASTPIN (-10250 5800) $PN 1
J 2
(-10260 5810);
DISPLAY 0.680851 (-10260 5810);
PAINT MONO (-10260 5810);
FORCEPROP 1 LAST $LOCATION R196
J 2
(-10350 5800);
DISPLAY 1.212766 (-10350 5800);
PAINT GREEN (-10350 5800);
FORCEPROP 1 LAST VALUE 100OHM
J 0
(-9961 5805);
DISPLAY 1.212766 (-9961 5805);
PAINT GREEN (-9961 5805);
FORCEPROP 0 LAST PACKAGE 0402
J 0
(-10200 5850);
DISPLAY 0.638298 (-10200 5850);
FORCEPROP 0 LAST CDS_SEC 1
J 0
(-9950 5900);
DISPLAY 1.021277 (-9950 5900);
DISPLAY INVISIBLE (-9950 5900);
FORCEPROP 0 LAST $SEC 1
J 0
(-9950 5900);
DISPLAY 0.680851 (-9950 5900);
PAINT MONO (-9950 5900);
DISPLAY INVISIBLE (-9950 5900);
FORCEPROP 0 LAST CDS_LOCATION R196
J 0
(-9950 5900);
DISPLAY 1.021277 (-9950 5900);
DISPLAY INVISIBLE (-9950 5900);
FORCEPROP 1 LAST PATH I332
J 0
(-10347 5905);
DISPLAY 1.212766 (-10347 5905);
PAINT GREEN (-10347 5905);
DISPLAY INVISIBLE (-10347 5905);
FORCEPROP 1 LAST TOLERANCE 1%
J 0
(-10347 6055);
DISPLAY 1.212766 (-10347 6055);
PAINT GREEN (-10347 6055);
DISPLAY INVISIBLE (-10347 6055);
FORCEPROP 1 LAST CLS_PN G155-11000-01
J 0
(-10286 6000);
DISPLAY 1.212766 (-10286 6000);
PAINT GREEN (-10286 6000);
DISPLAY INVISIBLE (-10286 6000);
FORCEPROP 2 LAST CDS_LIB passive
J 0
(-10150 5800);
DISPLAY INVISIBLE (-10150 5800);
FORCEPROP 1 LAST CDS_LMAN_SYM_OUTLINE -50,50,100,-50
J 0
(-10150 5800);
DISPLAY 0.468085 (-10150 5800);
PAINT GREEN (-10150 5800);
DISPLAY INVISIBLE (-10150 5800);
FORCEADD RESISTOR..1
(-9500 6450);
FORCEPROP 0 LASTPIN (-9350 6450) $PN 2
J 0
(-9340 6460);
DISPLAY 0.680851 (-9340 6460);
PAINT MONO (-9340 6460);
FORCEPROP 0 LASTPIN (-9600 6450) $PN 1
J 2
(-9610 6460);
DISPLAY 0.680851 (-9610 6460);
PAINT MONO (-9610 6460);
FORCEPROP 1 LAST $LOCATION R197
J 2
(-9700 6450);
DISPLAY 1.212766 (-9700 6450);
PAINT GREEN (-9700 6450);
FORCEPROP 0 LAST NO_ASSY TRUE
J 0
(-9650 6400);
DISPLAY 0.808511 (-9650 6400);
DISPLAY BOTH (-9650 6400);
FORCEPROP 1 LAST VALUE 100OHM
J 0
(-9311 6455);
DISPLAY 1.212766 (-9311 6455);
PAINT GREEN (-9311 6455);
FORCEPROP 0 LAST PACKAGE 0402
J 0
(-9550 6500);
DISPLAY 0.638298 (-9550 6500);
FORCEPROP 0 LAST CDS_SEC 1
J 0
(-9300 6550);
DISPLAY 1.021277 (-9300 6550);
DISPLAY INVISIBLE (-9300 6550);
FORCEPROP 0 LAST $SEC 1
J 0
(-9300 6550);
DISPLAY 0.680851 (-9300 6550);
PAINT MONO (-9300 6550);
DISPLAY INVISIBLE (-9300 6550);
FORCEPROP 0 LAST CDS_LOCATION R197
J 0
(-9300 6550);
DISPLAY 1.021277 (-9300 6550);
DISPLAY INVISIBLE (-9300 6550);
FORCEPROP 1 LAST PATH I333
J 0
(-9697 6555);
DISPLAY 1.212766 (-9697 6555);
PAINT GREEN (-9697 6555);
DISPLAY INVISIBLE (-9697 6555);
FORCEPROP 1 LAST TOLERANCE 1%
J 0
(-9697 6705);
DISPLAY 1.212766 (-9697 6705);
PAINT GREEN (-9697 6705);
DISPLAY INVISIBLE (-9697 6705);
FORCEPROP 1 LAST CLS_PN G155-11000-01
J 0
(-9636 6650);
DISPLAY 1.212766 (-9636 6650);
PAINT GREEN (-9636 6650);
DISPLAY INVISIBLE (-9636 6650);
FORCEPROP 1 LAST CDS_LMAN_SYM_OUTLINE -50,50,100,-50
J 0
(-9500 6450);
DISPLAY 0.468085 (-9500 6450);
PAINT GREEN (-9500 6450);
DISPLAY INVISIBLE (-9500 6450);
FORCEPROP 2 LAST CDS_LIB passive
J 0
(-9500 6450);
DISPLAY INVISIBLE (-9500 6450);
FORCEADD RESISTOR..1
(-9500 6150);
FORCEPROP 0 LASTPIN (-9350 6150) $PN 2
J 0
(-9340 6160);
DISPLAY 0.680851 (-9340 6160);
PAINT MONO (-9340 6160);
FORCEPROP 0 LASTPIN (-9600 6150) $PN 1
J 2
(-9610 6160);
DISPLAY 0.680851 (-9610 6160);
PAINT MONO (-9610 6160);
FORCEPROP 1 LAST $LOCATION R198
J 2
(-9700 6150);
DISPLAY 1.212766 (-9700 6150);
PAINT GREEN (-9700 6150);
FORCEPROP 0 LAST NO_ASSY TRUE
J 0
(-9650 6100);
DISPLAY 0.808511 (-9650 6100);
DISPLAY BOTH (-9650 6100);
FORCEPROP 1 LAST VALUE 100OHM
J 0
(-9311 6155);
DISPLAY 1.212766 (-9311 6155);
PAINT GREEN (-9311 6155);
FORCEPROP 0 LAST PACKAGE 0402
J 0
(-9550 6200);
DISPLAY 0.638298 (-9550 6200);
FORCEPROP 0 LAST CDS_SEC 1
J 0
(-9300 6250);
DISPLAY 1.021277 (-9300 6250);
DISPLAY INVISIBLE (-9300 6250);
FORCEPROP 0 LAST $SEC 1
J 0
(-9300 6250);
DISPLAY 0.680851 (-9300 6250);
PAINT MONO (-9300 6250);
DISPLAY INVISIBLE (-9300 6250);
FORCEPROP 0 LAST CDS_LOCATION R198
J 0
(-9300 6250);
DISPLAY 1.021277 (-9300 6250);
DISPLAY INVISIBLE (-9300 6250);
FORCEPROP 1 LAST PATH I334
J 0
(-9697 6255);
DISPLAY 1.212766 (-9697 6255);
PAINT GREEN (-9697 6255);
DISPLAY INVISIBLE (-9697 6255);
FORCEPROP 1 LAST TOLERANCE 1%
J 0
(-9697 6405);
DISPLAY 1.212766 (-9697 6405);
PAINT GREEN (-9697 6405);
DISPLAY INVISIBLE (-9697 6405);
FORCEPROP 2 LAST CDS_LIB passive
J 0
(-9500 6150);
DISPLAY INVISIBLE (-9500 6150);
FORCEPROP 1 LAST CDS_LMAN_SYM_OUTLINE -50,50,100,-50
J 0
(-9500 6150);
DISPLAY 0.468085 (-9500 6150);
PAINT GREEN (-9500 6150);
DISPLAY INVISIBLE (-9500 6150);
FORCEPROP 1 LAST CLS_PN G155-11000-01
J 0
(-9636 6350);
DISPLAY 1.212766 (-9636 6350);
PAINT GREEN (-9636 6350);
DISPLAY INVISIBLE (-9636 6350);
FORCEADD RESISTOR..1
(-5750 5150);
FORCEPROP 0 LASTPIN (-5600 5150) $PN 2
J 0
(-5590 5160);
DISPLAY 0.680851 (-5590 5160);
PAINT MONO (-5590 5160);
FORCEPROP 0 LASTPIN (-5850 5150) $PN 1
J 2
(-5860 5160);
DISPLAY 0.680851 (-5860 5160);
PAINT MONO (-5860 5160);
FORCEPROP 1 LAST $LOCATION R207
J 2
(-5900 5150);
DISPLAY 0.978723 (-5900 5150);
PAINT GREEN (-5900 5150);
FORCEPROP 1 LAST VALUE 0OHM
J 0
(-5511 5155);
DISPLAY 0.978723 (-5511 5155);
PAINT GREEN (-5511 5155);
FORCEPROP 0 LAST CDS_SEC 1
J 0
(-5500 5250);
DISPLAY 1.021277 (-5500 5250);
DISPLAY INVISIBLE (-5500 5250);
FORCEPROP 0 LAST $SEC 1
J 0
(-5500 5250);
DISPLAY 0.680851 (-5500 5250);
PAINT MONO (-5500 5250);
DISPLAY INVISIBLE (-5500 5250);
FORCEPROP 0 LAST CDS_LOCATION R207
J 0
(-5500 5250);
DISPLAY 1.021277 (-5500 5250);
DISPLAY INVISIBLE (-5500 5250);
FORCEPROP 1 LAST CLS_PN G155-100R0-J0
J 0
(-5886 5350);
DISPLAY 1.212766 (-5886 5350);
PAINT GREEN (-5886 5350);
DISPLAY INVISIBLE (-5886 5350);
FORCEPROP 1 LAST TOLERANCE -
J 0
(-5947 5405);
DISPLAY 1.212766 (-5947 5405);
PAINT GREEN (-5947 5405);
DISPLAY INVISIBLE (-5947 5405);
FORCEPROP 2 LAST CDS_LIB passive
J 0
(-5750 5150);
DISPLAY INVISIBLE (-5750 5150);
FORCEPROP 1 LAST CDS_LMAN_SYM_OUTLINE -50,50,100,-50
J 0
(-5750 5150);
DISPLAY 0.468085 (-5750 5150);
PAINT GREEN (-5750 5150);
DISPLAY INVISIBLE (-5750 5150);
FORCEPROP 1 LAST PATH I337
J 0
(-5947 5255);
DISPLAY 1.212766 (-5947 5255);
PAINT GREEN (-5947 5255);
DISPLAY INVISIBLE (-5947 5255);
FORCEADD RESISTOR..1
(-3600 4650);
FORCEPROP 0 LASTPIN (-3450 4650) $PN 2
J 0
(-3440 4660);
DISPLAY 0.680851 (-3440 4660);
PAINT MONO (-3440 4660);
FORCEPROP 0 LASTPIN (-3700 4650) $PN 1
J 2
(-3710 4660);
DISPLAY 0.680851 (-3710 4660);
PAINT MONO (-3710 4660);
FORCEPROP 1 LAST $LOCATION R210
J 2
(-3800 4650);
DISPLAY 1.212766 (-3800 4650);
PAINT GREEN (-3800 4650);
FORCEPROP 1 LAST VALUE 330OHM
J 0
(-3361 4655);
DISPLAY 1.212766 (-3361 4655);
PAINT GREEN (-3361 4655);
FORCEPROP 0 LAST CDS_SEC 1
J 0
(-3350 4750);
DISPLAY 1.021277 (-3350 4750);
DISPLAY INVISIBLE (-3350 4750);
FORCEPROP 0 LAST $SEC 1
J 0
(-3350 4750);
DISPLAY 0.680851 (-3350 4750);
PAINT MONO (-3350 4750);
DISPLAY INVISIBLE (-3350 4750);
FORCEPROP 0 LAST CDS_LOCATION R210
J 0
(-3350 4750);
DISPLAY 1.021277 (-3350 4750);
DISPLAY INVISIBLE (-3350 4750);
FORCEPROP 1 LAST PATH I338
J 0
(-3797 4755);
DISPLAY 1.212766 (-3797 4755);
PAINT GREEN (-3797 4755);
DISPLAY INVISIBLE (-3797 4755);
FORCEPROP 1 LAST TOLERANCE 1%
J 0
(-3797 4905);
DISPLAY 1.212766 (-3797 4905);
PAINT GREEN (-3797 4905);
DISPLAY INVISIBLE (-3797 4905);
FORCEPROP 1 LAST CLS_PN G155-13300-01
J 0
(-3736 4850);
DISPLAY 1.212766 (-3736 4850);
PAINT GREEN (-3736 4850);
DISPLAY INVISIBLE (-3736 4850);
FORCEPROP 2 LAST CDS_LIB passive
J 0
(-3600 4650);
DISPLAY INVISIBLE (-3600 4650);
FORCEPROP 1 LAST CDS_LMAN_SYM_OUTLINE -50,50,100,-50
J 0
(-3600 4650);
DISPLAY 0.468085 (-3600 4650);
PAINT GREEN (-3600 4650);
DISPLAY INVISIBLE (-3600 4650);
FORCEADD RESISTOR..1
(-3600 4750);
FORCEPROP 0 LASTPIN (-3450 4750) $PN 2
J 0
(-3440 4760);
DISPLAY 0.680851 (-3440 4760);
PAINT MONO (-3440 4760);
FORCEPROP 0 LASTPIN (-3700 4750) $PN 1
J 2
(-3710 4760);
DISPLAY 0.680851 (-3710 4760);
PAINT MONO (-3710 4760);
FORCEPROP 1 LAST $LOCATION R209
J 2
(-3800 4750);
DISPLAY 1.212766 (-3800 4750);
PAINT GREEN (-3800 4750);
FORCEPROP 1 LAST VALUE 4.7KOHM
J 0
(-3361 4755);
DISPLAY 1.212766 (-3361 4755);
PAINT GREEN (-3361 4755);
FORCEPROP 0 LAST CDS_SEC 1
J 0
(-3350 4850);
DISPLAY 1.021277 (-3350 4850);
DISPLAY INVISIBLE (-3350 4850);
FORCEPROP 0 LAST $SEC 1
J 0
(-3350 4850);
DISPLAY 0.680851 (-3350 4850);
PAINT MONO (-3350 4850);
DISPLAY INVISIBLE (-3350 4850);
FORCEPROP 0 LAST CDS_LOCATION R209
J 0
(-3350 4850);
DISPLAY 1.021277 (-3350 4850);
DISPLAY INVISIBLE (-3350 4850);
FORCEPROP 1 LAST PATH I339
J 0
(-3797 4855);
DISPLAY 1.212766 (-3797 4855);
PAINT GREEN (-3797 4855);
DISPLAY INVISIBLE (-3797 4855);
FORCEPROP 1 LAST TOLERANCE 1%
J 0
(-3797 5005);
DISPLAY 1.212766 (-3797 5005);
PAINT GREEN (-3797 5005);
DISPLAY INVISIBLE (-3797 5005);
FORCEPROP 1 LAST CLS_PN G155-14701-01
J 0
(-3736 4950);
DISPLAY 1.212766 (-3736 4950);
PAINT GREEN (-3736 4950);
DISPLAY INVISIBLE (-3736 4950);
FORCEPROP 1 LAST CDS_LMAN_SYM_OUTLINE -50,50,100,-50
J 0
(-3600 4750);
DISPLAY 0.468085 (-3600 4750);
PAINT GREEN (-3600 4750);
DISPLAY INVISIBLE (-3600 4750);
FORCEPROP 2 LAST CDS_LIB passive
J 0
(-3600 4750);
DISPLAY INVISIBLE (-3600 4750);
FORCEADD OFFPAGE_IN..1
(-11450 6250);
FORCEPROP 2 LAST $XR0 9E11> 
J 0
(-11633 6250);
DISPLAY 0.638298 (-11633 6250);
PAINT MONO (-11633 6250);
FORCEPROP 1 LAST CDS_LMAN_SYM_OUTLINE -50,50,50,-50
J 0
(-11450 6250);
DISPLAY 0.468085 (-11450 6250);
PAINT GREEN (-11450 6250);
DISPLAY INVISIBLE (-11450 6250);
FORCEPROP 2 LAST CDS_LIB cls
J 0
(-11450 6250);
DISPLAY INVISIBLE (-11450 6250);
FORCEPROP 2 LAST PATH I361
J 0
(-11600 6300);
DISPLAY 1.021277 (-11600 6300);
DISPLAY INVISIBLE (-11600 6300);
FORCEPROP 1 LAST OFFPAGE TRUE
J 0
(-11440 6305);
DISPLAY 0.808511 (-11440 6305);
PAINT GREEN (-11440 6305);
DISPLAY INVISIBLE (-11440 6305);
FORCEPROP 1 LAST BODY_TYPE COMMENT
J 0
(-11440 6385);
DISPLAY 0.808511 (-11440 6385);
PAINT GREEN (-11440 6385);
DISPLAY INVISIBLE (-11440 6385);
FORCEADD OFFPAGE_IN..1
(-11450 6350);
FORCEPROP 2 LAST $XR0 9E11> 
J 0
(-11633 6350);
DISPLAY 0.638298 (-11633 6350);
PAINT MONO (-11633 6350);
FORCEPROP 2 LAST PATH I362
J 0
(-11600 6400);
DISPLAY 1.021277 (-11600 6400);
DISPLAY INVISIBLE (-11600 6400);
FORCEPROP 1 LAST OFFPAGE TRUE
J 0
(-11440 6405);
DISPLAY 0.808511 (-11440 6405);
PAINT GREEN (-11440 6405);
DISPLAY INVISIBLE (-11440 6405);
FORCEPROP 1 LAST BODY_TYPE COMMENT
J 0
(-11440 6485);
DISPLAY 0.808511 (-11440 6485);
PAINT GREEN (-11440 6485);
DISPLAY INVISIBLE (-11440 6485);
FORCEPROP 1 LAST CDS_LMAN_SYM_OUTLINE -50,50,50,-50
J 0
(-11450 6350);
DISPLAY 0.468085 (-11450 6350);
PAINT GREEN (-11450 6350);
DISPLAY INVISIBLE (-11450 6350);
FORCEPROP 2 LAST CDS_LIB cls
J 0
(-11450 6350);
DISPLAY INVISIBLE (-11450 6350);
FORCEADD VCC..1
(-11800 5600);
FORCEPROP 3 LASTPIN (-11750 5550) SIG_NAME XP3R3V_FPGA\g
J 0
(-11740 5560);
DISPLAY 0.659574 (-11740 5560);
PAINT MONO (-11740 5560);
DISPLAY INVISIBLE (-11740 5560);
FORCEPROP 0 LAST VOLTAGE 3.3V
J 0
(-12050 5700);
DISPLAY 1.021277 (-12050 5700);
DISPLAY BOTH (-12050 5700);
FORCEPROP 1 LAST HDL_POWER XP3R3V_FPGA
J 1
(-11745 5655);
DISPLAY 1.021277 (-11745 5655);
PAINT GREEN (-11745 5655);
FORCEPROP 1 LAST PATH I385
J 0
(-11765 5690);
DISPLAY 0.808511 (-11765 5690);
PAINT GREEN (-11765 5690);
DISPLAY INVISIBLE (-11765 5690);
FORCEPROP 1 LAST BODY_TYPE PLUMBING
J 0
(-11845 5557);
DISPLAY 0.340426 (-11845 5557);
PAINT GREEN (-11845 5557);
DISPLAY INVISIBLE (-11845 5557);
FORCEPROP 1 LAST CDS_LMAN_SYM_OUTLINE -250,250,250,-250
J 0
(-11800 5600);
DISPLAY 0.468085 (-11800 5600);
PAINT GREEN (-11800 5600);
DISPLAY INVISIBLE (-11800 5600);
FORCEPROP 2 LAST CDS_LIB cls
J 0
(-11800 5600);
DISPLAY INVISIBLE (-11800 5600);
FORCEADD VCC..1
(-1050 3650);
FORCEPROP 3 LASTPIN (-1000 3600) SIG_NAME XP3R3V_FPGA\g
J 0
(-990 3610);
DISPLAY 0.659574 (-990 3610);
PAINT MONO (-990 3610);
DISPLAY INVISIBLE (-990 3610);
FORCEPROP 0 LAST VOLTAGE 3.3V
J 0
(-1300 3800);
DISPLAY 1.021277 (-1300 3800);
DISPLAY BOTH (-1300 3800);
FORCEPROP 1 LAST HDL_POWER XP3R3V_FPGA
J 1
(-995 3705);
DISPLAY 1.021277 (-995 3705);
PAINT GREEN (-995 3705);
FORCEPROP 1 LAST CDS_LMAN_SYM_OUTLINE -250,250,250,-250
J 0
(-1050 3650);
DISPLAY 0.468085 (-1050 3650);
PAINT GREEN (-1050 3650);
DISPLAY INVISIBLE (-1050 3650);
FORCEPROP 2 LAST CDS_LIB cls
J 0
(-1050 3650);
DISPLAY INVISIBLE (-1050 3650);
FORCEPROP 1 LAST BODY_TYPE PLUMBING
J 0
(-1095 3607);
DISPLAY 0.340426 (-1095 3607);
PAINT GREEN (-1095 3607);
DISPLAY INVISIBLE (-1095 3607);
FORCEPROP 1 LAST PATH I389
J 0
(-1015 3740);
DISPLAY 0.808511 (-1015 3740);
PAINT GREEN (-1015 3740);
DISPLAY INVISIBLE (-1015 3740);
FORCEADD VCC..1
(-2700 4900);
FORCEPROP 3 LASTPIN (-2650 4850) SIG_NAME XP3R3V_FPGA\g
J 0
(-2640 4860);
DISPLAY 0.659574 (-2640 4860);
PAINT MONO (-2640 4860);
DISPLAY INVISIBLE (-2640 4860);
FORCEPROP 1 LAST HDL_POWER XP3R3V_FPGA
J 1
(-2645 4955);
DISPLAY 1.021277 (-2645 4955);
PAINT GREEN (-2645 4955);
FORCEPROP 0 LAST VOLTAGE 3.3V
J 0
(-2950 5050);
DISPLAY 1.021277 (-2950 5050);
DISPLAY BOTH (-2950 5050);
FORCEPROP 1 LAST PATH I390
J 0
(-2665 4990);
DISPLAY 0.808511 (-2665 4990);
PAINT GREEN (-2665 4990);
DISPLAY INVISIBLE (-2665 4990);
FORCEPROP 1 LAST BODY_TYPE PLUMBING
J 0
(-2745 4857);
DISPLAY 0.340426 (-2745 4857);
PAINT GREEN (-2745 4857);
DISPLAY INVISIBLE (-2745 4857);
FORCEPROP 1 LAST CDS_LMAN_SYM_OUTLINE -250,250,250,-250
J 0
(-2700 4900);
DISPLAY 0.468085 (-2700 4900);
PAINT GREEN (-2700 4900);
DISPLAY INVISIBLE (-2700 4900);
FORCEPROP 2 LAST CDS_LIB cls
J 0
(-2700 4900);
DISPLAY INVISIBLE (-2700 4900);
FORCEADD RESISTOR..2
(-5000 2600);
FORCEPROP 0 LASTPIN (-5000 2450) $PN 2
R 1
J 2
(-5010 2440);
DISPLAY 0.680851 (-5010 2440);
PAINT MONO (-5010 2440);
FORCEPROP 0 LASTPIN (-5000 2700) $PN 1
R 1
J 0
(-5010 2710);
DISPLAY 0.680851 (-5010 2710);
PAINT MONO (-5010 2710);
FORCEPROP 1 LAST $LOCATION R216
J 0
(-4950 2450);
DISPLAY 1.212766 (-4950 2450);
PAINT GREEN (-4950 2450);
FORCEPROP 0 LAST PACKAGE 0402
J 0
(-4950 2550);
DISPLAY 1.021277 (-4950 2550);
FORCEPROP 1 LAST VALUE 1KOHM
J 0
(-4950 2650);
DISPLAY 1.212766 (-4950 2650);
PAINT GREEN (-4950 2650);
FORCEPROP 0 LAST CDS_SEC 1
J 0
(-4950 2750);
DISPLAY 1.021277 (-4950 2750);
DISPLAY INVISIBLE (-4950 2750);
FORCEPROP 0 LAST $SEC 1
J 0
(-4950 2750);
DISPLAY 0.680851 (-4950 2750);
PAINT MONO (-4950 2750);
DISPLAY INVISIBLE (-4950 2750);
FORCEPROP 0 LAST CDS_LOCATION R216
J 0
(-4950 2750);
DISPLAY 1.021277 (-4950 2750);
DISPLAY INVISIBLE (-4950 2750);
FORCEPROP 1 LAST CLS_PN G155-11001-01
J 0
(-5136 2800);
DISPLAY 1.212766 (-5136 2800);
PAINT GREEN (-5136 2800);
DISPLAY INVISIBLE (-5136 2800);
FORCEPROP 1 LAST CDS_LMAN_SYM_OUTLINE -50,50,50,-100
J 0
(-5000 2600);
DISPLAY 0.468085 (-5000 2600);
PAINT GREEN (-5000 2600);
DISPLAY INVISIBLE (-5000 2600);
FORCEPROP 2 LAST CDS_LIB passive
J 0
(-5000 2600);
DISPLAY INVISIBLE (-5000 2600);
FORCEPROP 1 LAST TOLERANCE 1%
J 0
(-5197 2855);
DISPLAY 1.212766 (-5197 2855);
PAINT GREEN (-5197 2855);
DISPLAY INVISIBLE (-5197 2855);
FORCEPROP 1 LAST PATH I391
J 0
(-5197 2705);
DISPLAY 1.212766 (-5197 2705);
PAINT GREEN (-5197 2705);
DISPLAY INVISIBLE (-5197 2705);
FORCEADD RESISTOR..2
(-4550 3250);
FORCEPROP 0 LASTPIN (-4550 3100) $PN 2
R 1
J 2
(-4560 3090);
DISPLAY 0.680851 (-4560 3090);
PAINT MONO (-4560 3090);
FORCEPROP 0 LASTPIN (-4550 3350) $PN 1
R 1
J 0
(-4560 3360);
DISPLAY 0.680851 (-4560 3360);
PAINT MONO (-4560 3360);
FORCEPROP 1 LAST $LOCATION R219
J 0
(-4500 3100);
DISPLAY 1.212766 (-4500 3100);
PAINT GREEN (-4500 3100);
FORCEPROP 1 LAST VALUE 10KOHM
J 0
(-4500 3300);
DISPLAY 1.212766 (-4500 3300);
PAINT GREEN (-4500 3300);
FORCEPROP 0 LAST PACKAGE 0402
J 0
(-4500 3350);
DISPLAY 1.021277 (-4500 3350);
FORCEPROP 0 LAST CDS_SEC 1
J 0
(-4500 3400);
DISPLAY 1.021277 (-4500 3400);
DISPLAY INVISIBLE (-4500 3400);
FORCEPROP 0 LAST $SEC 1
J 0
(-4500 3400);
DISPLAY 0.680851 (-4500 3400);
PAINT MONO (-4500 3400);
DISPLAY INVISIBLE (-4500 3400);
FORCEPROP 0 LAST CDS_LOCATION R219
J 0
(-4500 3400);
DISPLAY 1.021277 (-4500 3400);
DISPLAY INVISIBLE (-4500 3400);
FORCEPROP 1 LAST CLS_PN G155-11002-01
J 0
(-4686 3450);
DISPLAY 1.212766 (-4686 3450);
PAINT GREEN (-4686 3450);
DISPLAY INVISIBLE (-4686 3450);
FORCEPROP 1 LAST CDS_LMAN_SYM_OUTLINE -50,50,50,-100
J 0
(-4550 3250);
DISPLAY 0.468085 (-4550 3250);
PAINT GREEN (-4550 3250);
DISPLAY INVISIBLE (-4550 3250);
FORCEPROP 2 LAST CDS_LIB passive
J 0
(-4550 3250);
DISPLAY INVISIBLE (-4550 3250);
FORCEPROP 1 LAST TOLERANCE 1%
J 0
(-4747 3505);
DISPLAY 1.212766 (-4747 3505);
PAINT GREEN (-4747 3505);
DISPLAY INVISIBLE (-4747 3505);
FORCEPROP 1 LAST PATH I392
J 0
(-4747 3355);
DISPLAY 1.212766 (-4747 3355);
PAINT GREEN (-4747 3355);
DISPLAY INVISIBLE (-4747 3355);
FORCEADD RESISTOR..2
(-4550 2600);
FORCEPROP 0 LASTPIN (-4550 2450) $PN 2
R 1
J 2
(-4560 2440);
DISPLAY 0.680851 (-4560 2440);
PAINT MONO (-4560 2440);
FORCEPROP 0 LASTPIN (-4550 2700) $PN 1
R 1
J 0
(-4560 2710);
DISPLAY 0.680851 (-4560 2710);
PAINT MONO (-4560 2710);
FORCEPROP 1 LAST $LOCATION R220
J 0
(-4500 2450);
DISPLAY 1.212766 (-4500 2450);
PAINT GREEN (-4500 2450);
FORCEPROP 0 LAST PACKAGE 0402
J 0
(-4500 2550);
DISPLAY 1.021277 (-4500 2550);
FORCEPROP 1 LAST VALUE 1KOHM
J 0
(-4500 2650);
DISPLAY 1.212766 (-4500 2650);
PAINT GREEN (-4500 2650);
FORCEPROP 0 LAST NO_ASSY TRUE
J 0
(-4500 2400);
DISPLAY 0.808511 (-4500 2400);
DISPLAY BOTH (-4500 2400);
FORCEPROP 0 LAST CDS_SEC 1
J 0
(-4500 2750);
DISPLAY 1.021277 (-4500 2750);
DISPLAY INVISIBLE (-4500 2750);
FORCEPROP 0 LAST $SEC 1
J 0
(-4500 2750);
DISPLAY 0.680851 (-4500 2750);
PAINT MONO (-4500 2750);
DISPLAY INVISIBLE (-4500 2750);
FORCEPROP 0 LAST CDS_LOCATION R220
J 0
(-4500 2750);
DISPLAY 1.021277 (-4500 2750);
DISPLAY INVISIBLE (-4500 2750);
FORCEPROP 1 LAST CLS_PN G155-11001-01
J 0
(-4686 2800);
DISPLAY 1.212766 (-4686 2800);
PAINT GREEN (-4686 2800);
DISPLAY INVISIBLE (-4686 2800);
FORCEPROP 1 LAST CDS_LMAN_SYM_OUTLINE -50,50,50,-100
J 0
(-4550 2600);
DISPLAY 0.468085 (-4550 2600);
PAINT GREEN (-4550 2600);
DISPLAY INVISIBLE (-4550 2600);
FORCEPROP 2 LAST CDS_LIB passive
J 0
(-4550 2600);
DISPLAY INVISIBLE (-4550 2600);
FORCEPROP 1 LAST TOLERANCE 1%
J 0
(-4747 2855);
DISPLAY 1.212766 (-4747 2855);
PAINT GREEN (-4747 2855);
DISPLAY INVISIBLE (-4747 2855);
FORCEPROP 1 LAST PATH I393
J 0
(-4747 2705);
DISPLAY 1.212766 (-4747 2705);
PAINT GREEN (-4747 2705);
DISPLAY INVISIBLE (-4747 2705);
FORCEADD RESISTOR..2
(-5000 3250);
FORCEPROP 0 LASTPIN (-5000 3100) $PN 2
R 1
J 2
(-5010 3090);
DISPLAY 0.680851 (-5010 3090);
PAINT MONO (-5010 3090);
FORCEPROP 0 LASTPIN (-5000 3350) $PN 1
R 1
J 0
(-5010 3360);
DISPLAY 0.680851 (-5010 3360);
PAINT MONO (-5010 3360);
FORCEPROP 1 LAST $LOCATION R215
J 0
(-4950 3100);
DISPLAY 1.212766 (-4950 3100);
PAINT GREEN (-4950 3100);
FORCEPROP 0 LAST NO_ASSY TRUE
J 0
(-4950 3200);
DISPLAY 0.808511 (-4950 3200);
DISPLAY BOTH (-4950 3200);
FORCEPROP 1 LAST VALUE 10KOHM
J 0
(-4950 3300);
DISPLAY 1.212766 (-4950 3300);
PAINT GREEN (-4950 3300);
FORCEPROP 0 LAST PACKAGE 0402
J 0
(-4950 3350);
DISPLAY 1.021277 (-4950 3350);
FORCEPROP 0 LAST CDS_SEC 1
J 0
(-4950 3400);
DISPLAY 1.021277 (-4950 3400);
DISPLAY INVISIBLE (-4950 3400);
FORCEPROP 0 LAST $SEC 1
J 0
(-4950 3400);
DISPLAY 0.680851 (-4950 3400);
PAINT MONO (-4950 3400);
DISPLAY INVISIBLE (-4950 3400);
FORCEPROP 0 LAST CDS_LOCATION R215
J 0
(-4950 3400);
DISPLAY 1.021277 (-4950 3400);
DISPLAY INVISIBLE (-4950 3400);
FORCEPROP 1 LAST CLS_PN G155-11002-01
J 0
(-5136 3450);
DISPLAY 1.212766 (-5136 3450);
PAINT GREEN (-5136 3450);
DISPLAY INVISIBLE (-5136 3450);
FORCEPROP 1 LAST CDS_LMAN_SYM_OUTLINE -50,50,50,-100
J 0
(-5000 3250);
DISPLAY 0.468085 (-5000 3250);
PAINT GREEN (-5000 3250);
DISPLAY INVISIBLE (-5000 3250);
FORCEPROP 2 LAST CDS_LIB passive
J 0
(-5000 3250);
DISPLAY INVISIBLE (-5000 3250);
FORCEPROP 1 LAST TOLERANCE 1%
J 0
(-5197 3505);
DISPLAY 1.212766 (-5197 3505);
PAINT GREEN (-5197 3505);
DISPLAY INVISIBLE (-5197 3505);
FORCEPROP 1 LAST PATH I394
J 0
(-5197 3355);
DISPLAY 1.212766 (-5197 3355);
PAINT GREEN (-5197 3355);
DISPLAY INVISIBLE (-5197 3355);
FORCEADD RESISTOR..2
(-5500 3250);
FORCEPROP 0 LASTPIN (-5500 3100) $PN 2
R 1
J 2
(-5510 3090);
DISPLAY 0.680851 (-5510 3090);
PAINT MONO (-5510 3090);
FORCEPROP 0 LASTPIN (-5500 3350) $PN 1
R 1
J 0
(-5510 3360);
DISPLAY 0.680851 (-5510 3360);
PAINT MONO (-5510 3360);
FORCEPROP 1 LAST $LOCATION R213
J 0
(-5450 3100);
DISPLAY 1.212766 (-5450 3100);
PAINT GREEN (-5450 3100);
FORCEPROP 0 LAST PACKAGE 0402
J 0
(-5450 3350);
DISPLAY 1.021277 (-5450 3350);
FORCEPROP 1 LAST VALUE 10KOHM
J 0
(-5450 3300);
DISPLAY 1.212766 (-5450 3300);
PAINT GREEN (-5450 3300);
FORCEPROP 0 LAST NO_ASSY TRUE
J 0
(-5450 3200);
DISPLAY 0.808511 (-5450 3200);
DISPLAY BOTH (-5450 3200);
FORCEPROP 0 LAST CDS_SEC 1
J 0
(-5450 3400);
DISPLAY 1.021277 (-5450 3400);
DISPLAY INVISIBLE (-5450 3400);
FORCEPROP 0 LAST $SEC 1
J 0
(-5450 3400);
DISPLAY 0.680851 (-5450 3400);
PAINT MONO (-5450 3400);
DISPLAY INVISIBLE (-5450 3400);
FORCEPROP 0 LAST CDS_LOCATION R213
J 0
(-5450 3400);
DISPLAY 1.021277 (-5450 3400);
DISPLAY INVISIBLE (-5450 3400);
FORCEPROP 1 LAST CLS_PN G155-11002-01
J 0
(-5636 3450);
DISPLAY 1.212766 (-5636 3450);
PAINT GREEN (-5636 3450);
DISPLAY INVISIBLE (-5636 3450);
FORCEPROP 1 LAST CDS_LMAN_SYM_OUTLINE -50,50,50,-100
J 0
(-5500 3250);
DISPLAY 0.468085 (-5500 3250);
PAINT GREEN (-5500 3250);
DISPLAY INVISIBLE (-5500 3250);
FORCEPROP 2 LAST CDS_LIB passive
J 0
(-5500 3250);
DISPLAY INVISIBLE (-5500 3250);
FORCEPROP 1 LAST TOLERANCE 1%
J 0
(-5697 3505);
DISPLAY 1.212766 (-5697 3505);
PAINT GREEN (-5697 3505);
DISPLAY INVISIBLE (-5697 3505);
FORCEPROP 1 LAST PATH I396
J 0
(-5697 3355);
DISPLAY 1.212766 (-5697 3355);
PAINT GREEN (-5697 3355);
DISPLAY INVISIBLE (-5697 3355);
FORCEADD RESISTOR..2
(-5500 2600);
FORCEPROP 0 LASTPIN (-5500 2450) $PN 2
R 1
J 2
(-5510 2440);
DISPLAY 0.680851 (-5510 2440);
PAINT MONO (-5510 2440);
FORCEPROP 0 LASTPIN (-5500 2700) $PN 1
R 1
J 0
(-5510 2710);
DISPLAY 0.680851 (-5510 2710);
PAINT MONO (-5510 2710);
FORCEPROP 1 LAST $LOCATION R214
J 0
(-5450 2450);
DISPLAY 1.212766 (-5450 2450);
PAINT GREEN (-5450 2450);
FORCEPROP 0 LAST PACKAGE 0402
J 0
(-5450 2550);
DISPLAY 1.021277 (-5450 2550);
FORCEPROP 1 LAST VALUE 1KOHM
J 0
(-5450 2650);
DISPLAY 1.212766 (-5450 2650);
PAINT GREEN (-5450 2650);
FORCEPROP 0 LAST CDS_SEC 1
J 0
(-5450 2750);
DISPLAY 1.021277 (-5450 2750);
DISPLAY INVISIBLE (-5450 2750);
FORCEPROP 0 LAST $SEC 1
J 0
(-5450 2750);
DISPLAY 0.680851 (-5450 2750);
PAINT MONO (-5450 2750);
DISPLAY INVISIBLE (-5450 2750);
FORCEPROP 0 LAST CDS_LOCATION R214
J 0
(-5450 2750);
DISPLAY 1.021277 (-5450 2750);
DISPLAY INVISIBLE (-5450 2750);
FORCEPROP 1 LAST CLS_PN G155-11001-01
J 0
(-5636 2800);
DISPLAY 1.212766 (-5636 2800);
PAINT GREEN (-5636 2800);
DISPLAY INVISIBLE (-5636 2800);
FORCEPROP 1 LAST CDS_LMAN_SYM_OUTLINE -50,50,50,-100
J 0
(-5500 2600);
DISPLAY 0.468085 (-5500 2600);
PAINT GREEN (-5500 2600);
DISPLAY INVISIBLE (-5500 2600);
FORCEPROP 2 LAST CDS_LIB passive
J 0
(-5500 2600);
DISPLAY INVISIBLE (-5500 2600);
FORCEPROP 1 LAST TOLERANCE 1%
J 0
(-5697 2855);
DISPLAY 1.212766 (-5697 2855);
PAINT GREEN (-5697 2855);
DISPLAY INVISIBLE (-5697 2855);
FORCEPROP 1 LAST PATH I397
J 0
(-5697 2705);
DISPLAY 1.212766 (-5697 2705);
PAINT GREEN (-5697 2705);
DISPLAY INVISIBLE (-5697 2705);
FORCEADD GND_SG..1
(-4600 2250);
FORCEPROP 3 LASTPIN (-4550 2300) SIG_NAME SG\g
J 0
(-4540 2310);
DISPLAY 0.659574 (-4540 2310);
PAINT MONO (-4540 2310);
DISPLAY INVISIBLE (-4540 2310);
FORCEPROP 1 LAST HDL_POWER SG
J 1
(-4545 2155);
DISPLAY 0.808511 (-4545 2155);
PAINT GREEN (-4545 2155);
FORCEPROP 1 LAST PATH I398
J 0
(-4565 2250);
DISPLAY 0.808511 (-4565 2250);
PAINT GREEN (-4565 2250);
DISPLAY INVISIBLE (-4565 2250);
FORCEPROP 1 LAST BODY_TYPE PLUMBING
J 0
(-4585 2235);
DISPLAY 0.808511 (-4585 2235);
PAINT GREEN (-4585 2235);
DISPLAY INVISIBLE (-4585 2235);
FORCEPROP 1 LAST CDS_LMAN_SYM_OUTLINE 0,0,100,-50
J 0
(-4600 2250);
DISPLAY 0.468085 (-4600 2250);
PAINT GREEN (-4600 2250);
DISPLAY INVISIBLE (-4600 2250);
FORCEPROP 2 LAST CDS_LIB cls
J 0
(-4600 2250);
DISPLAY INVISIBLE (-4600 2250);
FORCEADD OFFPAGE_OUT..1
R 2
(-6600 3000);
FORCEPROP 2 LAST $XR0 12G5< 
J 0
(-6783 3000);
DISPLAY 0.638298 (-6783 3000);
PAINT MONO (-6783 3000);
FORCEPROP 1 LAST BODY_TYPE COMMENT
J 2
(-6610 3135);
DISPLAY 0.808511 (-6610 3135);
PAINT GREEN (-6610 3135);
DISPLAY INVISIBLE (-6610 3135);
FORCEPROP 1 LAST CDS_LMAN_SYM_OUTLINE -50,50,50,-50
J 2
(-6600 3000);
DISPLAY 0.468085 (-6600 3000);
PAINT GREEN (-6600 3000);
DISPLAY INVISIBLE (-6600 3000);
FORCEPROP 2 LAST CDS_LIB cls
J 0
(-6600 3000);
DISPLAY INVISIBLE (-6600 3000);
FORCEPROP 1 LAST OFFPAGE TRUE
J 2
(-6610 3055);
DISPLAY 0.808511 (-6610 3055);
PAINT GREEN (-6610 3055);
DISPLAY INVISIBLE (-6610 3055);
FORCEPROP 2 LAST PATH I399
J 0
(-6750 3050);
DISPLAY 1.021277 (-6750 3050);
DISPLAY INVISIBLE (-6750 3050);
FORCEADD OFFPAGE_OUT..1
R 2
(-6600 2900);
FORCEPROP 2 LAST $XR0 12G5< 
J 0
(-6783 2900);
DISPLAY 0.638298 (-6783 2900);
PAINT MONO (-6783 2900);
FORCEPROP 1 LAST BODY_TYPE COMMENT
J 2
(-6610 3035);
DISPLAY 0.808511 (-6610 3035);
PAINT GREEN (-6610 3035);
DISPLAY INVISIBLE (-6610 3035);
FORCEPROP 1 LAST CDS_LMAN_SYM_OUTLINE -50,50,50,-50
J 2
(-6600 2900);
DISPLAY 0.468085 (-6600 2900);
PAINT GREEN (-6600 2900);
DISPLAY INVISIBLE (-6600 2900);
FORCEPROP 2 LAST CDS_LIB cls
J 0
(-6600 2900);
DISPLAY INVISIBLE (-6600 2900);
FORCEPROP 1 LAST OFFPAGE TRUE
J 2
(-6610 2955);
DISPLAY 0.808511 (-6610 2955);
PAINT GREEN (-6610 2955);
DISPLAY INVISIBLE (-6610 2955);
FORCEPROP 2 LAST PATH I400
J 0
(-6750 2950);
DISPLAY 1.021277 (-6750 2950);
DISPLAY INVISIBLE (-6750 2950);
FORCEADD OFFPAGE_OUT..1
R 2
(-6600 2800);
FORCEPROP 2 LAST $XR0 12G5< 
J 0
(-6783 2800);
DISPLAY 0.638298 (-6783 2800);
PAINT MONO (-6783 2800);
FORCEPROP 1 LAST BODY_TYPE COMMENT
J 2
(-6610 2935);
DISPLAY 0.808511 (-6610 2935);
PAINT GREEN (-6610 2935);
DISPLAY INVISIBLE (-6610 2935);
FORCEPROP 1 LAST CDS_LMAN_SYM_OUTLINE -50,50,50,-50
J 2
(-6600 2800);
DISPLAY 0.468085 (-6600 2800);
PAINT GREEN (-6600 2800);
DISPLAY INVISIBLE (-6600 2800);
FORCEPROP 2 LAST CDS_LIB cls
J 0
(-6600 2800);
DISPLAY INVISIBLE (-6600 2800);
FORCEPROP 1 LAST OFFPAGE TRUE
J 2
(-6610 2855);
DISPLAY 0.808511 (-6610 2855);
PAINT GREEN (-6610 2855);
DISPLAY INVISIBLE (-6610 2855);
FORCEPROP 2 LAST PATH I401
J 0
(-6750 2850);
DISPLAY 1.021277 (-6750 2850);
DISPLAY INVISIBLE (-6750 2850);
FORCEADD RESISTOR..1
R 5
(-1500 3250);
FORCEPROP 0 LASTPIN (-1500 3100) $PN 2
R 1
J 2
(-1510 3090);
DISPLAY 0.680851 (-1510 3090);
PAINT MONO (-1510 3090);
FORCEPROP 0 LASTPIN (-1500 3350) $PN 1
R 1
J 0
(-1510 3360);
DISPLAY 0.680851 (-1510 3360);
PAINT MONO (-1510 3360);
FORCEPROP 1 LAST $LOCATION R217
J 2
(-1300 3150);
DISPLAY 1.212766 (-1300 3150);
PAINT GREEN (-1300 3150);
FORCEPROP 1 LAST VALUE 100OHM
J 0
(-1450 3250);
DISPLAY 1.212766 (-1450 3250);
PAINT GREEN (-1450 3250);
FORCEPROP 0 LAST PACKAGE 0402
J 0
(-1450 3350);
DISPLAY 1.021277 (-1450 3350);
FORCEPROP 0 LAST NO_ASSY TRUE
J 0
(-1450 3100);
DISPLAY 0.808511 (-1450 3100);
DISPLAY BOTH (-1450 3100);
FORCEPROP 0 LAST CDS_SEC 1
J 0
(-1450 3350);
DISPLAY 1.021277 (-1450 3350);
DISPLAY INVISIBLE (-1450 3350);
FORCEPROP 0 LAST $SEC 1
J 0
(-1450 3350);
DISPLAY 0.680851 (-1450 3350);
PAINT MONO (-1450 3350);
DISPLAY INVISIBLE (-1450 3350);
FORCEPROP 0 LAST CDS_LOCATION R217
J 0
(-1450 3350);
DISPLAY 1.021277 (-1450 3350);
DISPLAY INVISIBLE (-1450 3350);
FORCEPROP 1 LAST CLS_PN G155-11000-01
R 3
J 0
(-1300 3386);
DISPLAY 1.212766 (-1300 3386);
PAINT GREEN (-1300 3386);
DISPLAY INVISIBLE (-1300 3386);
FORCEPROP 1 LAST CDS_LMAN_SYM_OUTLINE -50,50,100,-50
R 3
J 0
(-1500 3250);
DISPLAY 0.468085 (-1500 3250);
PAINT GREEN (-1500 3250);
DISPLAY INVISIBLE (-1500 3250);
FORCEPROP 2 LAST CDS_LIB passive
J 0
(-1500 3250);
DISPLAY INVISIBLE (-1500 3250);
FORCEPROP 1 LAST TOLERANCE 1%
R 3
J 0
(-1245 3447);
DISPLAY 1.212766 (-1245 3447);
PAINT GREEN (-1245 3447);
DISPLAY INVISIBLE (-1245 3447);
FORCEPROP 1 LAST PATH I402
R 3
J 0
(-1395 3447);
DISPLAY 1.212766 (-1395 3447);
PAINT GREEN (-1395 3447);
DISPLAY INVISIBLE (-1395 3447);
FORCEADD RESISTOR..1
R 5
(-1000 3250);
FORCEPROP 0 LASTPIN (-1000 3100) $PN 2
R 1
J 2
(-1010 3090);
DISPLAY 0.680851 (-1010 3090);
PAINT MONO (-1010 3090);
FORCEPROP 0 LASTPIN (-1000 3350) $PN 1
R 1
J 0
(-1010 3360);
DISPLAY 0.680851 (-1010 3360);
PAINT MONO (-1010 3360);
FORCEPROP 1 LAST $LOCATION R221
J 2
(-800 3150);
DISPLAY 1.212766 (-800 3150);
PAINT GREEN (-800 3150);
FORCEPROP 1 LAST VALUE 100OHM
J 0
(-950 3250);
DISPLAY 1.212766 (-950 3250);
PAINT GREEN (-950 3250);
FORCEPROP 0 LAST PACKAGE 0402
J 0
(-950 3350);
DISPLAY 1.021277 (-950 3350);
FORCEPROP 0 LAST NO_ASSY TRUE
J 0
(-900 3100);
DISPLAY 0.808511 (-900 3100);
DISPLAY BOTH (-900 3100);
FORCEPROP 0 LAST CDS_SEC 1
J 0
(-950 3350);
DISPLAY 1.021277 (-950 3350);
DISPLAY INVISIBLE (-950 3350);
FORCEPROP 0 LAST $SEC 1
J 0
(-950 3350);
DISPLAY 0.680851 (-950 3350);
PAINT MONO (-950 3350);
DISPLAY INVISIBLE (-950 3350);
FORCEPROP 0 LAST CDS_LOCATION R221
J 0
(-950 3350);
DISPLAY 1.021277 (-950 3350);
DISPLAY INVISIBLE (-950 3350);
FORCEPROP 1 LAST CLS_PN G155-11000-01
R 3
J 0
(-800 3386);
DISPLAY 1.212766 (-800 3386);
PAINT GREEN (-800 3386);
DISPLAY INVISIBLE (-800 3386);
FORCEPROP 1 LAST CDS_LMAN_SYM_OUTLINE -50,50,100,-50
R 3
J 0
(-1000 3250);
DISPLAY 0.468085 (-1000 3250);
PAINT GREEN (-1000 3250);
DISPLAY INVISIBLE (-1000 3250);
FORCEPROP 2 LAST CDS_LIB passive
J 0
(-1000 3250);
DISPLAY INVISIBLE (-1000 3250);
FORCEPROP 1 LAST TOLERANCE 1%
R 3
J 0
(-745 3447);
DISPLAY 1.212766 (-745 3447);
PAINT GREEN (-745 3447);
DISPLAY INVISIBLE (-745 3447);
FORCEPROP 1 LAST PATH I403
R 3
J 0
(-895 3447);
DISPLAY 1.212766 (-895 3447);
PAINT GREEN (-895 3447);
DISPLAY INVISIBLE (-895 3447);
FORCEADD RESISTOR..1
R 5
(-2000 3250);
FORCEPROP 0 LASTPIN (-2000 3100) $PN 2
R 1
J 2
(-2010 3090);
DISPLAY 0.680851 (-2010 3090);
PAINT MONO (-2010 3090);
FORCEPROP 0 LASTPIN (-2000 3350) $PN 1
R 1
J 0
(-2010 3360);
DISPLAY 0.680851 (-2010 3360);
PAINT MONO (-2010 3360);
FORCEPROP 1 LAST $LOCATION R211
J 2
(-1800 3150);
DISPLAY 1.212766 (-1800 3150);
PAINT GREEN (-1800 3150);
FORCEPROP 0 LAST PACKAGE 0402
J 0
(-1950 3350);
DISPLAY 1.021277 (-1950 3350);
FORCEPROP 1 LAST VALUE 100OHM
J 0
(-1950 3250);
DISPLAY 1.212766 (-1950 3250);
PAINT GREEN (-1950 3250);
FORCEPROP 0 LAST CDS_SEC 1
J 0
(-1950 3350);
DISPLAY 1.021277 (-1950 3350);
DISPLAY INVISIBLE (-1950 3350);
FORCEPROP 0 LAST $SEC 1
J 0
(-1950 3350);
DISPLAY 0.680851 (-1950 3350);
PAINT MONO (-1950 3350);
DISPLAY INVISIBLE (-1950 3350);
FORCEPROP 0 LAST CDS_LOCATION R211
J 0
(-1950 3350);
DISPLAY 1.021277 (-1950 3350);
DISPLAY INVISIBLE (-1950 3350);
FORCEPROP 2 LAST CDS_LIB passive
J 0
(-2000 3250);
DISPLAY INVISIBLE (-2000 3250);
FORCEPROP 1 LAST CDS_LMAN_SYM_OUTLINE -50,50,100,-50
R 3
J 0
(-2000 3250);
DISPLAY 0.468085 (-2000 3250);
PAINT GREEN (-2000 3250);
DISPLAY INVISIBLE (-2000 3250);
FORCEPROP 1 LAST CLS_PN G155-11000-01
R 3
J 0
(-1800 3386);
DISPLAY 1.212766 (-1800 3386);
PAINT GREEN (-1800 3386);
DISPLAY INVISIBLE (-1800 3386);
FORCEPROP 1 LAST TOLERANCE 1%
R 3
J 0
(-1745 3447);
DISPLAY 1.212766 (-1745 3447);
PAINT GREEN (-1745 3447);
DISPLAY INVISIBLE (-1745 3447);
FORCEPROP 1 LAST PATH I404
R 3
J 0
(-1895 3447);
DISPLAY 1.212766 (-1895 3447);
PAINT GREEN (-1895 3447);
DISPLAY INVISIBLE (-1895 3447);
FORCEADD RESISTOR..1
R 5
(-1000 2600);
FORCEPROP 0 LASTPIN (-1000 2450) $PN 2
R 1
J 2
(-1010 2440);
DISPLAY 0.680851 (-1010 2440);
PAINT MONO (-1010 2440);
FORCEPROP 0 LASTPIN (-1000 2700) $PN 1
R 1
J 0
(-1010 2710);
DISPLAY 0.680851 (-1010 2710);
PAINT MONO (-1010 2710);
FORCEPROP 1 LAST $LOCATION R222
J 2
(-800 2500);
DISPLAY 1.212766 (-800 2500);
PAINT GREEN (-800 2500);
FORCEPROP 1 LAST VALUE 100OHM
J 0
(-950 2600);
DISPLAY 1.212766 (-950 2600);
PAINT GREEN (-950 2600);
FORCEPROP 0 LAST PACKAGE 0402
J 0
(-950 2750);
DISPLAY 1.021277 (-950 2750);
FORCEPROP 0 LAST CDS_SEC 1
J 0
(-950 2700);
DISPLAY 1.021277 (-950 2700);
DISPLAY INVISIBLE (-950 2700);
FORCEPROP 0 LAST $SEC 1
J 0
(-950 2700);
DISPLAY 0.680851 (-950 2700);
PAINT MONO (-950 2700);
DISPLAY INVISIBLE (-950 2700);
FORCEPROP 0 LAST CDS_LOCATION R222
J 0
(-950 2700);
DISPLAY 1.021277 (-950 2700);
DISPLAY INVISIBLE (-950 2700);
FORCEPROP 2 LAST CDS_LIB passive
J 0
(-1000 2600);
DISPLAY INVISIBLE (-1000 2600);
FORCEPROP 1 LAST CDS_LMAN_SYM_OUTLINE -50,50,100,-50
R 3
J 0
(-1000 2600);
DISPLAY 0.468085 (-1000 2600);
PAINT GREEN (-1000 2600);
DISPLAY INVISIBLE (-1000 2600);
FORCEPROP 1 LAST CLS_PN G155-11000-01
R 3
J 0
(-800 2736);
DISPLAY 1.212766 (-800 2736);
PAINT GREEN (-800 2736);
DISPLAY INVISIBLE (-800 2736);
FORCEPROP 1 LAST TOLERANCE 1%
R 3
J 0
(-745 2797);
DISPLAY 1.212766 (-745 2797);
PAINT GREEN (-745 2797);
DISPLAY INVISIBLE (-745 2797);
FORCEPROP 1 LAST PATH I405
R 3
J 0
(-895 2797);
DISPLAY 1.212766 (-895 2797);
PAINT GREEN (-895 2797);
DISPLAY INVISIBLE (-895 2797);
FORCEADD RESISTOR..1
R 5
(-1500 2600);
FORCEPROP 0 LASTPIN (-1500 2450) $PN 2
R 1
J 2
(-1510 2440);
DISPLAY 0.680851 (-1510 2440);
PAINT MONO (-1510 2440);
FORCEPROP 0 LASTPIN (-1500 2700) $PN 1
R 1
J 0
(-1510 2710);
DISPLAY 0.680851 (-1510 2710);
PAINT MONO (-1510 2710);
FORCEPROP 1 LAST $LOCATION R218
J 2
(-1300 2500);
DISPLAY 1.212766 (-1300 2500);
PAINT GREEN (-1300 2500);
FORCEPROP 1 LAST VALUE 100OHM
J 0
(-1450 2600);
DISPLAY 1.212766 (-1450 2600);
PAINT GREEN (-1450 2600);
FORCEPROP 0 LAST PACKAGE 0402
J 0
(-1450 2750);
DISPLAY 1.021277 (-1450 2750);
FORCEPROP 0 LAST CDS_SEC 1
J 0
(-1450 2700);
DISPLAY 1.021277 (-1450 2700);
DISPLAY INVISIBLE (-1450 2700);
FORCEPROP 0 LAST $SEC 1
J 0
(-1450 2700);
DISPLAY 0.680851 (-1450 2700);
PAINT MONO (-1450 2700);
DISPLAY INVISIBLE (-1450 2700);
FORCEPROP 0 LAST CDS_LOCATION R218
J 0
(-1450 2700);
DISPLAY 1.021277 (-1450 2700);
DISPLAY INVISIBLE (-1450 2700);
FORCEPROP 2 LAST CDS_LIB passive
J 0
(-1500 2600);
DISPLAY INVISIBLE (-1500 2600);
FORCEPROP 1 LAST CDS_LMAN_SYM_OUTLINE -50,50,100,-50
R 3
J 0
(-1500 2600);
DISPLAY 0.468085 (-1500 2600);
PAINT GREEN (-1500 2600);
DISPLAY INVISIBLE (-1500 2600);
FORCEPROP 1 LAST CLS_PN G155-11000-01
R 3
J 0
(-1300 2736);
DISPLAY 1.212766 (-1300 2736);
PAINT GREEN (-1300 2736);
DISPLAY INVISIBLE (-1300 2736);
FORCEPROP 1 LAST TOLERANCE 1%
R 3
J 0
(-1245 2797);
DISPLAY 1.212766 (-1245 2797);
PAINT GREEN (-1245 2797);
DISPLAY INVISIBLE (-1245 2797);
FORCEPROP 1 LAST PATH I406
R 3
J 0
(-1395 2797);
DISPLAY 1.212766 (-1395 2797);
PAINT GREEN (-1395 2797);
DISPLAY INVISIBLE (-1395 2797);
FORCEADD RESISTOR..1
R 5
(-2000 2600);
FORCEPROP 0 LASTPIN (-2000 2450) $PN 2
R 1
J 2
(-2010 2440);
DISPLAY 0.680851 (-2010 2440);
PAINT MONO (-2010 2440);
FORCEPROP 0 LASTPIN (-2000 2700) $PN 1
R 1
J 0
(-2010 2710);
DISPLAY 0.680851 (-2010 2710);
PAINT MONO (-2010 2710);
FORCEPROP 1 LAST $LOCATION R212
J 2
(-1800 2500);
DISPLAY 1.212766 (-1800 2500);
PAINT GREEN (-1800 2500);
FORCEPROP 0 LAST NO_ASSY TRUE
J 0
(-2000 2450);
DISPLAY 0.808511 (-2000 2450);
DISPLAY BOTH (-2000 2450);
FORCEPROP 0 LAST PACKAGE 0402
J 0
(-1950 2750);
DISPLAY 1.021277 (-1950 2750);
FORCEPROP 1 LAST VALUE 100OHM
J 0
(-1950 2600);
DISPLAY 1.212766 (-1950 2600);
PAINT GREEN (-1950 2600);
FORCEPROP 0 LAST CDS_SEC 1
J 0
(-1950 2700);
DISPLAY 1.021277 (-1950 2700);
DISPLAY INVISIBLE (-1950 2700);
FORCEPROP 0 LAST $SEC 1
J 0
(-1950 2700);
DISPLAY 0.680851 (-1950 2700);
PAINT MONO (-1950 2700);
DISPLAY INVISIBLE (-1950 2700);
FORCEPROP 0 LAST CDS_LOCATION R212
J 0
(-1950 2700);
DISPLAY 1.021277 (-1950 2700);
DISPLAY INVISIBLE (-1950 2700);
FORCEPROP 2 LAST CDS_LIB passive
J 0
(-2000 2600);
DISPLAY INVISIBLE (-2000 2600);
FORCEPROP 1 LAST CDS_LMAN_SYM_OUTLINE -50,50,100,-50
R 3
J 0
(-2000 2600);
DISPLAY 0.468085 (-2000 2600);
PAINT GREEN (-2000 2600);
DISPLAY INVISIBLE (-2000 2600);
FORCEPROP 1 LAST CLS_PN G155-11000-01
R 3
J 0
(-1800 2736);
DISPLAY 1.212766 (-1800 2736);
PAINT GREEN (-1800 2736);
DISPLAY INVISIBLE (-1800 2736);
FORCEPROP 1 LAST TOLERANCE 1%
R 3
J 0
(-1745 2797);
DISPLAY 1.212766 (-1745 2797);
PAINT GREEN (-1745 2797);
DISPLAY INVISIBLE (-1745 2797);
FORCEPROP 1 LAST PATH I407
R 3
J 0
(-1895 2797);
DISPLAY 1.212766 (-1895 2797);
PAINT GREEN (-1895 2797);
DISPLAY INVISIBLE (-1895 2797);
FORCEADD VCC..1
(-4600 3600);
FORCEPROP 3 LASTPIN (-4550 3550) SIG_NAME XP3R3V_FPGA\g
J 0
(-4540 3560);
DISPLAY 0.659574 (-4540 3560);
PAINT MONO (-4540 3560);
DISPLAY INVISIBLE (-4540 3560);
FORCEPROP 1 LAST HDL_POWER XP3R3V_FPGA
J 1
(-4545 3655);
DISPLAY 1.021277 (-4545 3655);
PAINT GREEN (-4545 3655);
FORCEPROP 0 LAST VOLTAGE 3.3V
J 0
(-4850 3750);
DISPLAY 1.021277 (-4850 3750);
DISPLAY BOTH (-4850 3750);
FORCEPROP 2 LAST CDS_LIB cls
J 0
(-4600 3600);
DISPLAY INVISIBLE (-4600 3600);
FORCEPROP 1 LAST CDS_LMAN_SYM_OUTLINE -250,250,250,-250
J 0
(-4600 3600);
DISPLAY 0.468085 (-4600 3600);
PAINT GREEN (-4600 3600);
DISPLAY INVISIBLE (-4600 3600);
FORCEPROP 1 LAST BODY_TYPE PLUMBING
J 0
(-4645 3557);
DISPLAY 0.340426 (-4645 3557);
PAINT GREEN (-4645 3557);
DISPLAY INVISIBLE (-4645 3557);
FORCEPROP 1 LAST PATH I409
J 0
(-4565 3690);
DISPLAY 0.808511 (-4565 3690);
PAINT GREEN (-4565 3690);
DISPLAY INVISIBLE (-4565 3690);
FORCEADD OFFPAGE_IN..2
(-4300 4950);
FORCEPROP 2 LAST $XR4 32H7> 
J 0
(-3505 4950);
DISPLAY 0.638298 (-3505 4950);
PAINT MONO (-3505 4950);
FORCEPROP 2 LAST $XR3 31K11> 
J 0
(-3700 4950);
DISPLAY 0.638298 (-3700 4950);
PAINT MONO (-3700 4950);
FORCEPROP 2 LAST $XR2 31D7> 
J 0
(-3855 4950);
DISPLAY 0.638298 (-3855 4950);
PAINT MONO (-3855 4950);
FORCEPROP 2 LAST $XR0 24F15> 
J 0
(-4245 4950);
DISPLAY 0.638298 (-4245 4950);
PAINT MONO (-4245 4950);
FORCEPROP 2 LAST $XR1 25C9<> 
J 0
(-4035 4950);
DISPLAY 0.638298 (-4035 4950);
PAINT MONO (-4035 4950);
FORCEPROP 1 LAST BODY_TYPE COMMENT
J 0
(-4290 5085);
DISPLAY 0.808511 (-4290 5085);
PAINT GREEN (-4290 5085);
DISPLAY INVISIBLE (-4290 5085);
FORCEPROP 1 LAST OFFPAGE TRUE
J 0
(-4290 5005);
DISPLAY 0.808511 (-4290 5005);
PAINT GREEN (-4290 5005);
DISPLAY INVISIBLE (-4290 5005);
FORCEPROP 2 LAST PATH I410
J 0
(-4250 5050);
DISPLAY 1.021277 (-4250 5050);
DISPLAY INVISIBLE (-4250 5050);
FORCEPROP 1 LAST CDS_LMAN_SYM_OUTLINE -50,50,50,-50
J 0
(-4300 4950);
DISPLAY 0.468085 (-4300 4950);
PAINT GREEN (-4300 4950);
DISPLAY INVISIBLE (-4300 4950);
FORCEPROP 2 LAST CDS_LIB cls
J 0
(-4300 4950);
DISPLAY INVISIBLE (-4300 4950);
FORCEADD OFFPAGE_IN..2
R 2
(-11000 4850);
FORCEPROP 2 LAST $XR0 9E15> 
J 0
(-11350 4850);
DISPLAY 0.638298 (-11350 4850);
PAINT MONO (-11350 4850);
FORCEPROP 2 LAST $XR1 25C9<> 
J 0
(-11183 4850);
DISPLAY 0.638298 (-11183 4850);
PAINT MONO (-11183 4850);
FORCEPROP 1 LAST BODY_TYPE COMMENT
J 2
(-11010 4985);
DISPLAY 0.808511 (-11010 4985);
PAINT GREEN (-11010 4985);
DISPLAY INVISIBLE (-11010 4985);
FORCEPROP 1 LAST CDS_LMAN_SYM_OUTLINE -50,50,50,-50
J 2
(-11000 4850);
DISPLAY 0.468085 (-11000 4850);
PAINT GREEN (-11000 4850);
DISPLAY INVISIBLE (-11000 4850);
FORCEPROP 2 LAST CDS_LIB cls
J 0
(-11000 4850);
DISPLAY INVISIBLE (-11000 4850);
FORCEPROP 1 LAST OFFPAGE TRUE
J 2
(-11010 4905);
DISPLAY 0.808511 (-11010 4905);
PAINT GREEN (-11010 4905);
DISPLAY INVISIBLE (-11010 4905);
FORCEPROP 2 LAST PATH I426
J 0
(-10950 4950);
DISPLAY 1.021277 (-10950 4950);
DISPLAY INVISIBLE (-10950 4950);
FORCEADD G200_10283_01..1
R 2
(-13250 650);
FORCEPROP 0 LASTPIN (-13850 -250) $PN 10
J 2
(-13860 -240);
DISPLAY 0.680851 (-13860 -240);
PAINT MONO (-13860 -240);
FORCEPROP 0 LASTPIN (-13150 -250) $PN 9
J 0
(-13140 -240);
DISPLAY 0.680851 (-13140 -240);
PAINT MONO (-13140 -240);
FORCEPROP 0 LASTPIN (-13850 -50) $PN 8
J 2
(-13860 -40);
DISPLAY 0.680851 (-13860 -40);
PAINT MONO (-13860 -40);
FORCEPROP 0 LASTPIN (-13150 -50) $PN 7
J 0
(-13140 -40);
DISPLAY 0.680851 (-13140 -40);
PAINT MONO (-13140 -40);
FORCEPROP 0 LASTPIN (-13850 150) $PN 6
J 2
(-13860 160);
DISPLAY 0.680851 (-13860 160);
PAINT MONO (-13860 160);
FORCEPROP 0 LASTPIN (-13150 150) $PN 5
J 0
(-13140 160);
DISPLAY 0.680851 (-13140 160);
PAINT MONO (-13140 160);
FORCEPROP 0 LASTPIN (-13850 350) $PN 4
J 2
(-13860 360);
DISPLAY 0.680851 (-13860 360);
PAINT MONO (-13860 360);
FORCEPROP 0 LASTPIN (-13150 350) $PN 3
J 0
(-13140 360);
DISPLAY 0.680851 (-13140 360);
PAINT MONO (-13140 360);
FORCEPROP 0 LASTPIN (-13850 550) $PN 2
J 2
(-13860 560);
DISPLAY 0.680851 (-13860 560);
PAINT MONO (-13860 560);
FORCEPROP 0 LASTPIN (-13150 550) $PN 1
J 0
(-13140 560);
DISPLAY 0.680851 (-13140 560);
PAINT MONO (-13140 560);
FORCEPROP 1 LAST $LOCATION J14
J 2
(-13600 700);
DISPLAY 1.212766 (-13600 700);
PAINT GREEN (-13600 700);
FORCEPROP 1 LAST CLS_PN G200-10283-01
J 2
(-12950 -500);
DISPLAY 1.212766 (-12950 -500);
PAINT GREEN (-12950 -500);
FORCEPROP 0 LAST PART_NUMBER 95278-101A10LF
J 0
(-13650 -600);
DISPLAY 1.021277 (-13650 -600);
FORCEPROP 0 LAST CDS_SEC 1
J 0
(-13250 900);
DISPLAY 1.021277 (-13250 900);
DISPLAY INVISIBLE (-13250 900);
FORCEPROP 0 LAST $SEC 1
J 0
(-13250 900);
DISPLAY 0.680851 (-13250 900);
PAINT MONO (-13250 900);
DISPLAY INVISIBLE (-13250 900);
FORCEPROP 0 LAST CDS_LOCATION J14
J 0
(-13250 900);
DISPLAY 1.021277 (-13250 900);
DISPLAY INVISIBLE (-13250 900);
FORCEPROP 2 LASTPIN (-13850 350) SIG_NAME UN$127$G2001028301$I427$4
J 0
(-13840 360);
DISPLAY 0.659574 (-13840 360);
PAINT MONO (-13840 360);
DISPLAY INVISIBLE (-13840 360);
FORCEPROP 2 LAST CDS_LIB connector
J 0
(-13250 650);
DISPLAY INVISIBLE (-13250 650);
FORCEPROP 1 LAST CDS_LMAN_SYM_OUTLINE 0,0,500,-1000
J 2
(-13250 650);
DISPLAY 0.468085 (-13250 650);
PAINT GREEN (-13250 650);
DISPLAY INVISIBLE (-13250 650);
FORCEPROP 1 LAST PATH I427
J 2
(-13300 700);
DISPLAY 1.212766 (-13300 700);
PAINT GREEN (-13300 700);
DISPLAY INVISIBLE (-13300 700);
FORCEADD OFFPAGE_OUT..1
(-9400 1600);
FORCEPROP 2 LAST $XR1 10E5< 
J 0
(-9165 1600);
DISPLAY 0.638298 (-9165 1600);
PAINT MONO (-9165 1600);
FORCEPROP 2 LAST $XR0 9D10> 
J 0
(-9345 1600);
DISPLAY 0.638298 (-9345 1600);
PAINT MONO (-9345 1600);
FORCEPROP 2 LAST PATH I428
J 0
(-9150 1650);
DISPLAY 1.021277 (-9150 1650);
DISPLAY INVISIBLE (-9150 1650);
FORCEPROP 1 LAST OFFPAGE TRUE
J 0
(-9390 1655);
DISPLAY 0.808511 (-9390 1655);
PAINT GREEN (-9390 1655);
DISPLAY INVISIBLE (-9390 1655);
FORCEPROP 1 LAST BODY_TYPE COMMENT
J 0
(-9390 1735);
DISPLAY 0.808511 (-9390 1735);
PAINT GREEN (-9390 1735);
DISPLAY INVISIBLE (-9390 1735);
FORCEPROP 1 LAST CDS_LMAN_SYM_OUTLINE -50,50,50,-50
J 0
(-9400 1600);
DISPLAY 0.468085 (-9400 1600);
PAINT GREEN (-9400 1600);
DISPLAY INVISIBLE (-9400 1600);
FORCEPROP 2 LAST CDS_LIB cls
J 0
(-9400 1600);
DISPLAY INVISIBLE (-9400 1600);
FORCEADD OFFPAGE_OUT..1
(-9400 1200);
FORCEPROP 2 LAST $XR1 10F5< 
J 0
(-9165 1200);
DISPLAY 0.638298 (-9165 1200);
PAINT MONO (-9165 1200);
FORCEPROP 2 LAST $XR0 9D10> 
J 0
(-9345 1200);
DISPLAY 0.638298 (-9345 1200);
PAINT MONO (-9345 1200);
FORCEPROP 2 LAST PATH I429
J 0
(-9150 1250);
DISPLAY 1.021277 (-9150 1250);
DISPLAY INVISIBLE (-9150 1250);
FORCEPROP 1 LAST OFFPAGE TRUE
J 0
(-9390 1255);
DISPLAY 0.808511 (-9390 1255);
PAINT GREEN (-9390 1255);
DISPLAY INVISIBLE (-9390 1255);
FORCEPROP 2 LAST CDS_LIB cls
J 0
(-9400 1200);
DISPLAY INVISIBLE (-9400 1200);
FORCEPROP 1 LAST CDS_LMAN_SYM_OUTLINE -50,50,50,-50
J 0
(-9400 1200);
DISPLAY 0.468085 (-9400 1200);
PAINT GREEN (-9400 1200);
DISPLAY INVISIBLE (-9400 1200);
FORCEPROP 1 LAST BODY_TYPE COMMENT
J 0
(-9390 1335);
DISPLAY 0.808511 (-9390 1335);
PAINT GREEN (-9390 1335);
DISPLAY INVISIBLE (-9390 1335);
FORCEADD OFFPAGE_OUT..1
(-9400 1050);
FORCEPROP 2 LAST $XR0 9D10> 
J 0
(-9345 1050);
DISPLAY 0.638298 (-9345 1050);
PAINT MONO (-9345 1050);
FORCEPROP 2 LAST $XR1 10E5< 
J 0
(-9165 1050);
DISPLAY 0.638298 (-9165 1050);
PAINT MONO (-9165 1050);
FORCEPROP 2 LAST PATH I430
J 0
(-9150 1100);
DISPLAY 1.021277 (-9150 1100);
DISPLAY INVISIBLE (-9150 1100);
FORCEPROP 1 LAST OFFPAGE TRUE
J 0
(-9390 1105);
DISPLAY 0.808511 (-9390 1105);
PAINT GREEN (-9390 1105);
DISPLAY INVISIBLE (-9390 1105);
FORCEPROP 1 LAST BODY_TYPE COMMENT
J 0
(-9390 1185);
DISPLAY 0.808511 (-9390 1185);
PAINT GREEN (-9390 1185);
DISPLAY INVISIBLE (-9390 1185);
FORCEPROP 1 LAST CDS_LMAN_SYM_OUTLINE -50,50,50,-50
J 0
(-9400 1050);
DISPLAY 0.468085 (-9400 1050);
PAINT GREEN (-9400 1050);
DISPLAY INVISIBLE (-9400 1050);
FORCEPROP 2 LAST CDS_LIB cls
J 0
(-9400 1050);
DISPLAY INVISIBLE (-9400 1050);
FORCEADD OFFPAGE_IN..2
(-9400 1400);
FORCEPROP 2 LAST $XR1 9D10< 
J 0
(-9165 1400);
DISPLAY 0.638298 (-9165 1400);
PAINT MONO (-9165 1400);
FORCEPROP 2 LAST $XR0 10E5> 
J 0
(-9345 1400);
DISPLAY 0.638298 (-9345 1400);
PAINT MONO (-9345 1400);
FORCEPROP 2 LAST PATH I431
J 0
(-9150 1450);
DISPLAY 1.021277 (-9150 1450);
DISPLAY INVISIBLE (-9150 1450);
FORCEPROP 1 LAST OFFPAGE TRUE
J 0
(-9390 1455);
DISPLAY 0.808511 (-9390 1455);
PAINT GREEN (-9390 1455);
DISPLAY INVISIBLE (-9390 1455);
FORCEPROP 1 LAST BODY_TYPE COMMENT
J 0
(-9390 1535);
DISPLAY 0.808511 (-9390 1535);
PAINT GREEN (-9390 1535);
DISPLAY INVISIBLE (-9390 1535);
FORCEPROP 1 LAST CDS_LMAN_SYM_OUTLINE -50,50,50,-50
J 0
(-9400 1400);
DISPLAY 0.468085 (-9400 1400);
PAINT GREEN (-9400 1400);
DISPLAY INVISIBLE (-9400 1400);
FORCEPROP 2 LAST CDS_LIB cls
J 0
(-9400 1400);
DISPLAY INVISIBLE (-9400 1400);
FORCEADD RESISTOR..2
(-10450 1950);
FORCEPROP 0 LASTPIN (-10450 1800) $PN 2
R 1
J 2
(-10460 1790);
DISPLAY 0.680851 (-10460 1790);
PAINT MONO (-10460 1790);
FORCEPROP 0 LASTPIN (-10450 2050) $PN 1
R 1
J 0
(-10460 2060);
DISPLAY 0.680851 (-10460 2060);
PAINT MONO (-10460 2060);
FORCEPROP 1 LAST $LOCATION R405
J 0
(-10400 1850);
DISPLAY 1.212766 (-10400 1850);
PAINT GREEN (-10400 1850);
FORCEPROP 1 LAST VALUE 10KOHM
J 0
(-10400 2000);
DISPLAY 0.978723 (-10400 2000);
PAINT GREEN (-10400 2000);
FORCEPROP 0 LAST PACKAGE 0402
J 0
(-10350 2100);
DISPLAY 1.021277 (-10350 2100);
FORCEPROP 0 LAST CDS_SEC 1
J 0
(-10350 2150);
DISPLAY 1.021277 (-10350 2150);
DISPLAY INVISIBLE (-10350 2150);
FORCEPROP 0 LAST $SEC 1
J 0
(-10350 2150);
DISPLAY 0.680851 (-10350 2150);
PAINT MONO (-10350 2150);
DISPLAY INVISIBLE (-10350 2150);
FORCEPROP 0 LAST CDS_LOCATION R405
J 0
(-10350 2150);
DISPLAY 1.021277 (-10350 2150);
DISPLAY INVISIBLE (-10350 2150);
FORCEPROP 2 LAST CDS_LIB passive
J 0
(-10450 1950);
DISPLAY INVISIBLE (-10450 1950);
FORCEPROP 1 LAST CDS_LMAN_SYM_OUTLINE -50,50,50,-100
J 0
(-10450 1950);
DISPLAY 0.468085 (-10450 1950);
PAINT GREEN (-10450 1950);
DISPLAY INVISIBLE (-10450 1950);
FORCEPROP 1 LAST CLS_PN G155-11002-01
J 0
(-10586 2150);
DISPLAY 1.212766 (-10586 2150);
PAINT GREEN (-10586 2150);
DISPLAY INVISIBLE (-10586 2150);
FORCEPROP 1 LAST TOLERANCE 1%
J 0
(-10647 2205);
DISPLAY 1.212766 (-10647 2205);
PAINT GREEN (-10647 2205);
DISPLAY INVISIBLE (-10647 2205);
FORCEPROP 1 LAST PATH I432
J 0
(-10647 2055);
DISPLAY 1.212766 (-10647 2055);
PAINT GREEN (-10647 2055);
DISPLAY INVISIBLE (-10647 2055);
FORCEADD VCC..1
(-10500 2400);
FORCEPROP 3 LASTPIN (-10450 2350) SIG_NAME XP3R3V_FPGA\g
J 0
(-10440 2360);
DISPLAY 0.659574 (-10440 2360);
PAINT MONO (-10440 2360);
DISPLAY INVISIBLE (-10440 2360);
FORCEPROP 1 LAST HDL_POWER XP3R3V_FPGA
J 1
(-10445 2455);
DISPLAY 1.021277 (-10445 2455);
PAINT GREEN (-10445 2455);
FORCEPROP 0 LAST VOLTAGE 3.3V
J 0
(-10750 2550);
DISPLAY 1.021277 (-10750 2550);
DISPLAY BOTH (-10750 2550);
FORCEPROP 1 LAST CDS_LMAN_SYM_OUTLINE -250,250,250,-250
J 0
(-10500 2400);
DISPLAY 0.468085 (-10500 2400);
PAINT GREEN (-10500 2400);
DISPLAY INVISIBLE (-10500 2400);
FORCEPROP 2 LAST CDS_LIB cls
J 0
(-10500 2400);
DISPLAY INVISIBLE (-10500 2400);
FORCEPROP 1 LAST BODY_TYPE PLUMBING
J 0
(-10545 2357);
DISPLAY 0.340426 (-10545 2357);
PAINT GREEN (-10545 2357);
DISPLAY INVISIBLE (-10545 2357);
FORCEPROP 1 LAST PATH I433
J 0
(-10465 2490);
DISPLAY 0.808511 (-10465 2490);
PAINT GREEN (-10465 2490);
DISPLAY INVISIBLE (-10465 2490);
FORCEADD RESISTOR..2
(-10800 1950);
FORCEPROP 0 LASTPIN (-10800 1800) $PN 2
R 1
J 2
(-10810 1790);
DISPLAY 0.680851 (-10810 1790);
PAINT MONO (-10810 1790);
FORCEPROP 0 LASTPIN (-10800 2050) $PN 1
R 1
J 0
(-10810 2060);
DISPLAY 0.680851 (-10810 2060);
PAINT MONO (-10810 2060);
FORCEPROP 1 LAST $LOCATION R404
J 0
(-10750 1850);
DISPLAY 1.212766 (-10750 1850);
PAINT GREEN (-10750 1850);
FORCEPROP 1 LAST VALUE 10KOHM
J 0
(-10750 2000);
DISPLAY 0.978723 (-10750 2000);
PAINT GREEN (-10750 2000);
FORCEPROP 0 LAST PACKAGE 0402
J 0
(-10700 2100);
DISPLAY 1.021277 (-10700 2100);
FORCEPROP 0 LAST CDS_SEC 1
J 0
(-10700 2150);
DISPLAY 1.021277 (-10700 2150);
DISPLAY INVISIBLE (-10700 2150);
FORCEPROP 0 LAST $SEC 1
J 0
(-10700 2150);
DISPLAY 0.680851 (-10700 2150);
PAINT MONO (-10700 2150);
DISPLAY INVISIBLE (-10700 2150);
FORCEPROP 0 LAST CDS_LOCATION R404
J 0
(-10700 2150);
DISPLAY 1.021277 (-10700 2150);
DISPLAY INVISIBLE (-10700 2150);
FORCEPROP 1 LAST CLS_PN G155-11002-01
J 0
(-10936 2150);
DISPLAY 1.212766 (-10936 2150);
PAINT GREEN (-10936 2150);
DISPLAY INVISIBLE (-10936 2150);
FORCEPROP 1 LAST CDS_LMAN_SYM_OUTLINE -50,50,50,-100
J 0
(-10800 1950);
DISPLAY 0.468085 (-10800 1950);
PAINT GREEN (-10800 1950);
DISPLAY INVISIBLE (-10800 1950);
FORCEPROP 2 LAST CDS_LIB passive
J 0
(-10800 1950);
DISPLAY INVISIBLE (-10800 1950);
FORCEPROP 1 LAST TOLERANCE 1%
J 0
(-10997 2205);
DISPLAY 1.212766 (-10997 2205);
PAINT GREEN (-10997 2205);
DISPLAY INVISIBLE (-10997 2205);
FORCEPROP 1 LAST PATH I434
J 0
(-10997 2055);
DISPLAY 1.212766 (-10997 2055);
PAINT GREEN (-10997 2055);
DISPLAY INVISIBLE (-10997 2055);
FORCEADD RESISTOR..2
(-11150 1950);
FORCEPROP 0 LASTPIN (-11150 1800) $PN 2
R 1
J 2
(-11160 1790);
DISPLAY 0.680851 (-11160 1790);
PAINT MONO (-11160 1790);
FORCEPROP 0 LASTPIN (-11150 2050) $PN 1
R 1
J 0
(-11160 2060);
DISPLAY 0.680851 (-11160 2060);
PAINT MONO (-11160 2060);
FORCEPROP 1 LAST $LOCATION R403
J 0
(-11100 1850);
DISPLAY 1.212766 (-11100 1850);
PAINT GREEN (-11100 1850);
FORCEPROP 0 LAST PACKAGE 0402
J 0
(-11050 2100);
DISPLAY 1.021277 (-11050 2100);
FORCEPROP 1 LAST VALUE 10KOHM
J 0
(-11100 2000);
DISPLAY 0.978723 (-11100 2000);
PAINT GREEN (-11100 2000);
FORCEPROP 0 LAST CDS_SEC 1
J 0
(-11050 2150);
DISPLAY 1.021277 (-11050 2150);
DISPLAY INVISIBLE (-11050 2150);
FORCEPROP 0 LAST $SEC 1
J 0
(-11050 2150);
DISPLAY 0.680851 (-11050 2150);
PAINT MONO (-11050 2150);
DISPLAY INVISIBLE (-11050 2150);
FORCEPROP 0 LAST CDS_LOCATION R403
J 0
(-11050 2150);
DISPLAY 1.021277 (-11050 2150);
DISPLAY INVISIBLE (-11050 2150);
FORCEPROP 1 LAST CLS_PN G155-11002-01
J 0
(-11286 2150);
DISPLAY 1.212766 (-11286 2150);
PAINT GREEN (-11286 2150);
DISPLAY INVISIBLE (-11286 2150);
FORCEPROP 1 LAST CDS_LMAN_SYM_OUTLINE -50,50,50,-100
J 0
(-11150 1950);
DISPLAY 0.468085 (-11150 1950);
PAINT GREEN (-11150 1950);
DISPLAY INVISIBLE (-11150 1950);
FORCEPROP 2 LAST CDS_LIB passive
J 0
(-11150 1950);
DISPLAY INVISIBLE (-11150 1950);
FORCEPROP 1 LAST TOLERANCE 1%
J 0
(-11347 2205);
DISPLAY 1.212766 (-11347 2205);
PAINT GREEN (-11347 2205);
DISPLAY INVISIBLE (-11347 2205);
FORCEPROP 1 LAST PATH I435
J 0
(-11347 2055);
DISPLAY 1.212766 (-11347 2055);
PAINT GREEN (-11347 2055);
DISPLAY INVISIBLE (-11347 2055);
FORCEADD RESISTOR..1
(-11800 1600);
FORCEPROP 0 LASTPIN (-11650 1600) $PN 2
J 0
(-11640 1610);
DISPLAY 0.680851 (-11640 1610);
PAINT MONO (-11640 1610);
FORCEPROP 0 LASTPIN (-11900 1600) $PN 1
J 2
(-11910 1610);
DISPLAY 0.680851 (-11910 1610);
PAINT MONO (-11910 1610);
FORCEPROP 1 LAST $LOCATION R134
J 2
(-12000 1600);
DISPLAY 1.212766 (-12000 1600);
PAINT GREEN (-12000 1600);
FORCEPROP 0 LAST PACKAGE 0402
J 0
(-11850 1650);
DISPLAY 1.021277 (-11850 1650);
FORCEPROP 1 LAST VALUE 33OHM
J 0
(-11600 1600);
DISPLAY 1.234043 (-11600 1600);
PAINT GREEN (-11600 1600);
FORCEPROP 0 LAST CDS_SEC 1
J 0
(-11600 1700);
DISPLAY 1.021277 (-11600 1700);
DISPLAY INVISIBLE (-11600 1700);
FORCEPROP 0 LAST $SEC 1
J 0
(-11600 1700);
DISPLAY 0.680851 (-11600 1700);
PAINT MONO (-11600 1700);
DISPLAY INVISIBLE (-11600 1700);
FORCEPROP 0 LAST CDS_LOCATION R134
J 0
(-11600 1700);
DISPLAY 1.021277 (-11600 1700);
DISPLAY INVISIBLE (-11600 1700);
FORCEPROP 2 LAST SIGNAL_MODEL DEFAULT_RESISTOR_33OHM_2_1
J 0
(-11950 1800);
DISPLAY 1.021277 (-11950 1800);
DISPLAY INVISIBLE (-11950 1800);
FORCEPROP 1 LAST CDS_LMAN_SYM_OUTLINE -50,50,100,-50
J 0
(-11800 1600);
DISPLAY 0.468085 (-11800 1600);
PAINT GREEN (-11800 1600);
DISPLAY INVISIBLE (-11800 1600);
FORCEPROP 2 LAST CDS_LIB passive
J 0
(-11800 1600);
DISPLAY INVISIBLE (-11800 1600);
FORCEPROP 1 LAST CLS_PN G155-133R0-01
J 0
(-11936 1800);
DISPLAY 1.212766 (-11936 1800);
PAINT GREEN (-11936 1800);
DISPLAY INVISIBLE (-11936 1800);
FORCEPROP 1 LAST TOLERANCE 1%
J 0
(-11997 1855);
DISPLAY 1.212766 (-11997 1855);
PAINT GREEN (-11997 1855);
DISPLAY INVISIBLE (-11997 1855);
FORCEPROP 1 LAST PATH I436
J 0
(-11997 1705);
DISPLAY 1.212766 (-11997 1705);
PAINT GREEN (-11997 1705);
DISPLAY INVISIBLE (-11997 1705);
FORCEADD RESISTOR..1
(-11800 1200);
FORCEPROP 0 LASTPIN (-11650 1200) $PN 2
J 0
(-11640 1210);
DISPLAY 0.680851 (-11640 1210);
PAINT MONO (-11640 1210);
FORCEPROP 0 LASTPIN (-11900 1200) $PN 1
J 2
(-11910 1210);
DISPLAY 0.680851 (-11910 1210);
PAINT MONO (-11910 1210);
FORCEPROP 1 LAST $LOCATION R136
J 2
(-12000 1200);
DISPLAY 1.212766 (-12000 1200);
PAINT GREEN (-12000 1200);
FORCEPROP 0 LAST PACKAGE 0402
J 0
(-11850 1250);
DISPLAY 1.021277 (-11850 1250);
FORCEPROP 1 LAST VALUE 33OHM
J 0
(-11600 1200);
DISPLAY 1.234043 (-11600 1200);
PAINT GREEN (-11600 1200);
FORCEPROP 0 LAST CDS_SEC 1
J 0
(-11600 1300);
DISPLAY 1.021277 (-11600 1300);
DISPLAY INVISIBLE (-11600 1300);
FORCEPROP 0 LAST $SEC 1
J 0
(-11600 1300);
DISPLAY 0.680851 (-11600 1300);
PAINT MONO (-11600 1300);
DISPLAY INVISIBLE (-11600 1300);
FORCEPROP 0 LAST CDS_LOCATION R136
J 0
(-11600 1300);
DISPLAY 1.021277 (-11600 1300);
DISPLAY INVISIBLE (-11600 1300);
FORCEPROP 1 LAST CLS_PN G155-133R0-01
J 0
(-11936 1400);
DISPLAY 1.212766 (-11936 1400);
PAINT GREEN (-11936 1400);
DISPLAY INVISIBLE (-11936 1400);
FORCEPROP 1 LAST TOLERANCE 1%
J 0
(-11997 1455);
DISPLAY 1.212766 (-11997 1455);
PAINT GREEN (-11997 1455);
DISPLAY INVISIBLE (-11997 1455);
FORCEPROP 1 LAST PATH I437
J 0
(-11997 1305);
DISPLAY 1.212766 (-11997 1305);
PAINT GREEN (-11997 1305);
DISPLAY INVISIBLE (-11997 1305);
FORCEPROP 1 LAST CDS_LMAN_SYM_OUTLINE -50,50,100,-50
J 0
(-11800 1200);
DISPLAY 0.468085 (-11800 1200);
PAINT GREEN (-11800 1200);
DISPLAY INVISIBLE (-11800 1200);
FORCEPROP 2 LAST CDS_LIB passive
J 0
(-11800 1200);
DISPLAY INVISIBLE (-11800 1200);
FORCEADD RESISTOR..1
(-11800 1400);
FORCEPROP 0 LASTPIN (-11650 1400) $PN 2
J 0
(-11640 1410);
DISPLAY 0.680851 (-11640 1410);
PAINT MONO (-11640 1410);
FORCEPROP 0 LASTPIN (-11900 1400) $PN 1
J 2
(-11910 1410);
DISPLAY 0.680851 (-11910 1410);
PAINT MONO (-11910 1410);
FORCEPROP 1 LAST $LOCATION R135
J 2
(-12000 1400);
DISPLAY 1.212766 (-12000 1400);
PAINT GREEN (-12000 1400);
FORCEPROP 0 LAST PACKAGE 0402
J 0
(-11850 1450);
DISPLAY 1.021277 (-11850 1450);
FORCEPROP 1 LAST VALUE 0OHM
J 0
(-11600 1400);
DISPLAY 1.234043 (-11600 1400);
PAINT GREEN (-11600 1400);
FORCEPROP 0 LAST CDS_SEC 1
J 0
(-11600 1500);
DISPLAY 1.021277 (-11600 1500);
DISPLAY INVISIBLE (-11600 1500);
FORCEPROP 0 LAST $SEC 1
J 0
(-11600 1500);
DISPLAY 0.680851 (-11600 1500);
PAINT MONO (-11600 1500);
DISPLAY INVISIBLE (-11600 1500);
FORCEPROP 0 LAST CDS_LOCATION R135
J 0
(-11600 1500);
DISPLAY 1.021277 (-11600 1500);
DISPLAY INVISIBLE (-11600 1500);
FORCEPROP 1 LAST CDS_LMAN_SYM_OUTLINE -50,50,100,-50
J 0
(-11800 1400);
DISPLAY 0.468085 (-11800 1400);
PAINT GREEN (-11800 1400);
DISPLAY INVISIBLE (-11800 1400);
FORCEPROP 2 LAST CDS_LIB passive
J 0
(-11800 1400);
DISPLAY INVISIBLE (-11800 1400);
FORCEPROP 1 LAST PATH I438
J 0
(-11997 1505);
DISPLAY 1.212766 (-11997 1505);
PAINT GREEN (-11997 1505);
DISPLAY INVISIBLE (-11997 1505);
FORCEPROP 1 LAST TOLERANCE -
J 0
(-11997 1655);
DISPLAY 1.212766 (-11997 1655);
PAINT GREEN (-11997 1655);
DISPLAY INVISIBLE (-11997 1655);
FORCEPROP 1 LAST CLS_PN G155-100R0-J0
J 0
(-11936 1600);
DISPLAY 1.212766 (-11936 1600);
PAINT GREEN (-11936 1600);
DISPLAY INVISIBLE (-11936 1600);
FORCEADD RESISTOR..1
(-11800 1050);
FORCEPROP 0 LASTPIN (-11650 1050) $PN 2
J 0
(-11640 1060);
DISPLAY 0.680851 (-11640 1060);
PAINT MONO (-11640 1060);
FORCEPROP 0 LASTPIN (-11900 1050) $PN 1
J 2
(-11910 1060);
DISPLAY 0.680851 (-11910 1060);
PAINT MONO (-11910 1060);
FORCEPROP 1 LAST $LOCATION R137
J 2
(-12000 1050);
DISPLAY 1.212766 (-12000 1050);
PAINT GREEN (-12000 1050);
FORCEPROP 0 LAST PACKAGE 0402
J 0
(-11850 1100);
DISPLAY 1.021277 (-11850 1100);
FORCEPROP 1 LAST VALUE 33OHM
J 0
(-11600 1050);
DISPLAY 1.234043 (-11600 1050);
PAINT GREEN (-11600 1050);
FORCEPROP 0 LAST CDS_SEC 1
J 0
(-11600 1150);
DISPLAY 1.021277 (-11600 1150);
DISPLAY INVISIBLE (-11600 1150);
FORCEPROP 0 LAST $SEC 1
J 0
(-11600 1150);
DISPLAY 0.680851 (-11600 1150);
PAINT MONO (-11600 1150);
DISPLAY INVISIBLE (-11600 1150);
FORCEPROP 0 LAST CDS_LOCATION R137
J 0
(-11600 1150);
DISPLAY 1.021277 (-11600 1150);
DISPLAY INVISIBLE (-11600 1150);
FORCEPROP 2 LAST SIGNAL_MODEL DEFAULT_RESISTOR_33OHM_2_1
J 0
(-11950 1250);
DISPLAY 1.021277 (-11950 1250);
DISPLAY INVISIBLE (-11950 1250);
FORCEPROP 1 LAST CDS_LMAN_SYM_OUTLINE -50,50,100,-50
J 0
(-11800 1050);
DISPLAY 0.468085 (-11800 1050);
PAINT GREEN (-11800 1050);
DISPLAY INVISIBLE (-11800 1050);
FORCEPROP 2 LAST CDS_LIB passive
J 0
(-11800 1050);
DISPLAY INVISIBLE (-11800 1050);
FORCEPROP 1 LAST CLS_PN G155-133R0-01
J 0
(-11936 1250);
DISPLAY 1.212766 (-11936 1250);
PAINT GREEN (-11936 1250);
DISPLAY INVISIBLE (-11936 1250);
FORCEPROP 1 LAST TOLERANCE 1%
J 0
(-11997 1305);
DISPLAY 1.212766 (-11997 1305);
PAINT GREEN (-11997 1305);
DISPLAY INVISIBLE (-11997 1305);
FORCEPROP 1 LAST PATH I439
J 0
(-11997 1155);
DISPLAY 1.212766 (-11997 1155);
PAINT GREEN (-11997 1155);
DISPLAY INVISIBLE (-11997 1155);
FORCEADD RESISTOR..2
(-10250 800);
FORCEPROP 0 LASTPIN (-10250 650) $PN 2
R 1
J 2
(-10260 640);
DISPLAY 0.680851 (-10260 640);
PAINT MONO (-10260 640);
FORCEPROP 0 LASTPIN (-10250 900) $PN 1
R 1
J 0
(-10260 910);
DISPLAY 0.680851 (-10260 910);
PAINT MONO (-10260 910);
FORCEPROP 1 LAST $LOCATION R402
J 0
(-10150 650);
DISPLAY 1.212766 (-10150 650);
PAINT GREEN (-10150 650);
FORCEPROP 1 LAST VALUE 2.2KOHM
J 0
(-10150 750);
DISPLAY 0.978723 (-10150 750);
PAINT GREEN (-10150 750);
FORCEPROP 0 LAST PACKAGE 0402
J 0
(-10150 850);
DISPLAY 1.021277 (-10150 850);
FORCEPROP 0 LAST CDS_SEC 1
J 0
(-10150 900);
DISPLAY 1.021277 (-10150 900);
DISPLAY INVISIBLE (-10150 900);
FORCEPROP 0 LAST $SEC 1
J 0
(-10150 900);
DISPLAY 0.680851 (-10150 900);
PAINT MONO (-10150 900);
DISPLAY INVISIBLE (-10150 900);
FORCEPROP 0 LAST CDS_LOCATION R402
J 0
(-10150 900);
DISPLAY 1.021277 (-10150 900);
DISPLAY INVISIBLE (-10150 900);
FORCEPROP 1 LAST CLS_PN G155-12201-01
J 0
(-10386 1000);
DISPLAY 1.212766 (-10386 1000);
PAINT GREEN (-10386 1000);
DISPLAY INVISIBLE (-10386 1000);
FORCEPROP 2 LAST CDS_LIB passive
J 0
(-10250 800);
DISPLAY INVISIBLE (-10250 800);
FORCEPROP 1 LAST CDS_LMAN_SYM_OUTLINE -50,50,50,-100
J 0
(-10250 800);
DISPLAY 0.468085 (-10250 800);
PAINT GREEN (-10250 800);
DISPLAY INVISIBLE (-10250 800);
FORCEPROP 1 LAST TOLERANCE 1%
J 0
(-10447 1055);
DISPLAY 1.212766 (-10447 1055);
PAINT GREEN (-10447 1055);
DISPLAY INVISIBLE (-10447 1055);
FORCEPROP 1 LAST PATH I440
J 0
(-10447 905);
DISPLAY 1.212766 (-10447 905);
PAINT GREEN (-10447 905);
DISPLAY INVISIBLE (-10447 905);
FORCEADD GND_SG..1
(-10300 450);
FORCEPROP 3 LASTPIN (-10250 500) SIG_NAME SG\g
J 0
(-10240 510);
DISPLAY 0.659574 (-10240 510);
PAINT MONO (-10240 510);
DISPLAY INVISIBLE (-10240 510);
FORCEPROP 1 LAST HDL_POWER SG
J 1
(-10245 355);
DISPLAY 0.808511 (-10245 355);
PAINT GREEN (-10245 355);
FORCEPROP 1 LAST PATH I441
J 0
(-10265 450);
DISPLAY 0.808511 (-10265 450);
PAINT GREEN (-10265 450);
DISPLAY INVISIBLE (-10265 450);
FORCEPROP 1 LAST BODY_TYPE PLUMBING
J 0
(-10285 435);
DISPLAY 0.808511 (-10285 435);
PAINT GREEN (-10285 435);
DISPLAY INVISIBLE (-10285 435);
FORCEPROP 2 LAST CDS_LIB cls
J 0
(-10300 450);
DISPLAY INVISIBLE (-10300 450);
FORCEPROP 1 LAST CDS_LMAN_SYM_OUTLINE 0,0,100,-50
J 0
(-10300 450);
DISPLAY 0.468085 (-10300 450);
PAINT GREEN (-10300 450);
DISPLAY INVISIBLE (-10300 450);
FORCEADD DIODE_4_V1..1
R 1
(-11450 -200);
FORCEPROP 0 LASTPIN (-11350 300) $PN 4
R 1
J 0
(-11360 310);
DISPLAY 0.680851 (-11360 310);
PAINT MONO (-11360 310);
FORCEPROP 0 LASTPIN (-11100 300) $PN 3
R 1
J 0
(-11110 310);
DISPLAY 0.680851 (-11110 310);
PAINT MONO (-11110 310);
FORCEPROP 0 LASTPIN (-11050 -300) $PN 2
R 1
J 2
(-11060 -310);
DISPLAY 0.680851 (-11060 -310);
PAINT MONO (-11060 -310);
FORCEPROP 0 LASTPIN (-11350 -300) $PN 1
R 1
J 2
(-11360 -310);
DISPLAY 0.680851 (-11360 -310);
PAINT MONO (-11360 -310);
FORCEPROP 1 LAST LOCATION CR7
J 0
(-10700 -750);
DISPLAY 1.212766 (-10700 -750);
PAINT GREEN (-10700 -750);
FORCEPROP 0 LAST PART_NUMBER SR3.3.TCT
J 0
(-11250 -500);
DISPLAY 1.021277 (-11250 -500);
FORCEPROP 1 LAST CLS_PN G122-10123-01
J 0
(-11250 -600);
DISPLAY 1.212766 (-11250 -600);
PAINT GREEN (-11250 -600);
FORCEPROP 0 LAST CDS_SEC 1
R 1
J 0
(-11250 -450);
DISPLAY 1.021277 (-11250 -450);
DISPLAY INVISIBLE (-11250 -450);
FORCEPROP 0 LAST $SEC 1
R 1
J 0
(-11250 -450);
DISPLAY 0.680851 (-11250 -450);
PAINT MONO (-11250 -450);
DISPLAY INVISIBLE (-11250 -450);
FORCEPROP 2 LAST CDS_LIB discrete
J 0
(-11450 -200);
DISPLAY INVISIBLE (-11450 -200);
FORCEPROP 1 LAST CDS_LMAN_SYM_OUTLINE 0,0,400,-600
R 1
J 0
(-11450 -200);
DISPLAY 0.468085 (-11450 -200);
PAINT GREEN (-11450 -200);
DISPLAY INVISIBLE (-11450 -200);
FORCEPROP 1 LAST PATH I442
R 1
J 0
(-11500 -150);
DISPLAY 1.212766 (-11500 -150);
PAINT GREEN (-11500 -150);
DISPLAY INVISIBLE (-11500 -150);
FORCEADD DIODE_4_V1..1
R 1
(-12250 -200);
FORCEPROP 0 LASTPIN (-12150 300) $PN 4
R 1
J 0
(-12160 310);
DISPLAY 0.680851 (-12160 310);
PAINT MONO (-12160 310);
FORCEPROP 0 LASTPIN (-11900 300) $PN 3
R 1
J 0
(-11910 310);
DISPLAY 0.680851 (-11910 310);
PAINT MONO (-11910 310);
FORCEPROP 0 LASTPIN (-11850 -300) $PN 2
R 1
J 2
(-11860 -310);
DISPLAY 0.680851 (-11860 -310);
PAINT MONO (-11860 -310);
FORCEPROP 0 LASTPIN (-12150 -300) $PN 1
R 1
J 2
(-12160 -310);
DISPLAY 0.680851 (-12160 -310);
PAINT MONO (-12160 -310);
FORCEPROP 1 LAST LOCATION CR6
J 0
(-11500 -750);
DISPLAY 1.212766 (-11500 -750);
PAINT GREEN (-11500 -750);
FORCEPROP 0 LAST PART_NUMBER SR3.3.TCT
J 0
(-12050 -500);
DISPLAY 1.021277 (-12050 -500);
FORCEPROP 1 LAST CLS_PN G122-10123-01
J 0
(-12050 -600);
DISPLAY 1.212766 (-12050 -600);
PAINT GREEN (-12050 -600);
FORCEPROP 0 LAST CDS_SEC 1
R 1
J 0
(-12050 -450);
DISPLAY 1.021277 (-12050 -450);
DISPLAY INVISIBLE (-12050 -450);
FORCEPROP 0 LAST $SEC 1
R 1
J 0
(-12050 -450);
DISPLAY 0.680851 (-12050 -450);
PAINT MONO (-12050 -450);
DISPLAY INVISIBLE (-12050 -450);
FORCEPROP 2 LAST CDS_LIB discrete
J 0
(-12250 -200);
DISPLAY INVISIBLE (-12250 -200);
FORCEPROP 1 LAST CDS_LMAN_SYM_OUTLINE 0,0,400,-600
R 1
J 0
(-12250 -200);
DISPLAY 0.468085 (-12250 -200);
PAINT GREEN (-12250 -200);
DISPLAY INVISIBLE (-12250 -200);
FORCEPROP 1 LAST PATH I443
R 1
J 0
(-12300 -150);
DISPLAY 1.212766 (-12300 -150);
PAINT GREEN (-12300 -150);
DISPLAY INVISIBLE (-12300 -150);
FORCEADD GND_SG..1
(-12200 -500);
FORCEPROP 3 LASTPIN (-12150 -450) SIG_NAME SG\g
J 0
(-12140 -440);
DISPLAY 0.659574 (-12140 -440);
PAINT MONO (-12140 -440);
DISPLAY INVISIBLE (-12140 -440);
FORCEPROP 1 LAST HDL_POWER SG
J 1
(-12145 -595);
DISPLAY 0.808511 (-12145 -595);
PAINT GREEN (-12145 -595);
FORCEPROP 2 LAST CDS_LIB cls
J 0
(-12200 -500);
DISPLAY INVISIBLE (-12200 -500);
FORCEPROP 1 LAST CDS_LMAN_SYM_OUTLINE 0,0,100,-50
J 0
(-12200 -500);
DISPLAY 0.468085 (-12200 -500);
PAINT GREEN (-12200 -500);
DISPLAY INVISIBLE (-12200 -500);
FORCEPROP 1 LAST BODY_TYPE PLUMBING
J 0
(-12185 -515);
DISPLAY 0.808511 (-12185 -515);
PAINT GREEN (-12185 -515);
DISPLAY INVISIBLE (-12185 -515);
FORCEPROP 1 LAST PATH I444
J 0
(-12165 -500);
DISPLAY 0.808511 (-12165 -500);
PAINT GREEN (-12165 -500);
DISPLAY INVISIBLE (-12165 -500);
FORCEADD GND_SG..1
(-14050 -500);
FORCEPROP 3 LASTPIN (-14000 -450) SIG_NAME SG\g
J 0
(-13990 -440);
DISPLAY 0.659574 (-13990 -440);
PAINT MONO (-13990 -440);
DISPLAY INVISIBLE (-13990 -440);
FORCEPROP 1 LAST HDL_POWER SG
J 1
(-13995 -595);
DISPLAY 0.808511 (-13995 -595);
PAINT GREEN (-13995 -595);
FORCEPROP 1 LAST CDS_LMAN_SYM_OUTLINE 0,0,100,-50
J 0
(-14050 -500);
DISPLAY 0.468085 (-14050 -500);
PAINT GREEN (-14050 -500);
DISPLAY INVISIBLE (-14050 -500);
FORCEPROP 2 LAST CDS_LIB cls
J 0
(-14050 -500);
DISPLAY INVISIBLE (-14050 -500);
FORCEPROP 1 LAST BODY_TYPE PLUMBING
J 0
(-14035 -515);
DISPLAY 0.808511 (-14035 -515);
PAINT GREEN (-14035 -515);
DISPLAY INVISIBLE (-14035 -515);
FORCEPROP 1 LAST PATH I445
J 0
(-14015 -500);
DISPLAY 0.808511 (-14015 -500);
PAINT GREEN (-14015 -500);
DISPLAY INVISIBLE (-14015 -500);
FORCEADD RESISTOR..1
(-14300 350);
FORCEPROP 0 LASTPIN (-14150 350) $PN 2
J 0
(-14140 360);
DISPLAY 0.680851 (-14140 360);
PAINT MONO (-14140 360);
FORCEPROP 0 LASTPIN (-14400 350) $PN 1
J 2
(-14410 360);
DISPLAY 0.680851 (-14410 360);
PAINT MONO (-14410 360);
FORCEPROP 1 LAST $LOCATION R133
J 2
(-14150 400);
DISPLAY 1.212766 (-14150 400);
PAINT GREEN (-14150 400);
FORCEPROP 1 LAST VALUE 33OHM
J 0
(-14400 250);
DISPLAY 1.234043 (-14400 250);
PAINT GREEN (-14400 250);
FORCEPROP 0 LAST CDS_SEC 1
J 0
(-14100 450);
DISPLAY 1.021277 (-14100 450);
DISPLAY INVISIBLE (-14100 450);
FORCEPROP 0 LAST $SEC 1
J 0
(-14100 450);
DISPLAY 0.680851 (-14100 450);
PAINT MONO (-14100 450);
DISPLAY INVISIBLE (-14100 450);
FORCEPROP 0 LAST CDS_LOCATION R133
J 0
(-14100 450);
DISPLAY 1.021277 (-14100 450);
DISPLAY INVISIBLE (-14100 450);
FORCEPROP 2 LAST CDS_LIB passive
J 0
(-14300 350);
DISPLAY INVISIBLE (-14300 350);
FORCEPROP 1 LAST CDS_LMAN_SYM_OUTLINE -50,50,100,-50
J 0
(-14300 350);
DISPLAY 0.468085 (-14300 350);
PAINT GREEN (-14300 350);
DISPLAY INVISIBLE (-14300 350);
FORCEPROP 2 LAST SIGNAL_MODEL DEFAULT_RESISTOR_33OHM_2_1
J 0
(-14450 550);
DISPLAY 1.021277 (-14450 550);
DISPLAY INVISIBLE (-14450 550);
FORCEPROP 1 LAST CLS_PN G155-133R0-01
J 0
(-14436 550);
DISPLAY 1.212766 (-14436 550);
PAINT GREEN (-14436 550);
DISPLAY INVISIBLE (-14436 550);
FORCEPROP 1 LAST TOLERANCE 1%
J 0
(-14497 605);
DISPLAY 1.212766 (-14497 605);
PAINT GREEN (-14497 605);
DISPLAY INVISIBLE (-14497 605);
FORCEPROP 1 LAST PATH I446
J 0
(-14497 455);
DISPLAY 1.212766 (-14497 455);
PAINT GREEN (-14497 455);
DISPLAY INVISIBLE (-14497 455);
FORCEADD VCC..1
(-14550 550);
FORCEPROP 3 LASTPIN (-14500 500) SIG_NAME XP3R3V_FPGA\g
J 0
(-14490 510);
DISPLAY 0.659574 (-14490 510);
PAINT MONO (-14490 510);
DISPLAY INVISIBLE (-14490 510);
FORCEPROP 0 LAST VOLTAGE 3.3V
J 0
(-14800 700);
DISPLAY 1.021277 (-14800 700);
DISPLAY BOTH (-14800 700);
FORCEPROP 1 LAST HDL_POWER XP3R3V_FPGA
J 1
(-14495 605);
DISPLAY 1.021277 (-14495 605);
PAINT GREEN (-14495 605);
FORCEPROP 1 LAST PATH I447
J 0
(-14515 640);
DISPLAY 0.808511 (-14515 640);
PAINT GREEN (-14515 640);
DISPLAY INVISIBLE (-14515 640);
FORCEPROP 1 LAST BODY_TYPE PLUMBING
J 0
(-14595 507);
DISPLAY 0.340426 (-14595 507);
PAINT GREEN (-14595 507);
DISPLAY INVISIBLE (-14595 507);
FORCEPROP 2 LAST CDS_LIB cls
J 0
(-14550 550);
DISPLAY INVISIBLE (-14550 550);
FORCEPROP 1 LAST CDS_LMAN_SYM_OUTLINE -250,250,250,-250
J 0
(-14550 550);
DISPLAY 0.468085 (-14550 550);
PAINT GREEN (-14550 550);
DISPLAY INVISIBLE (-14550 550);
FORCEADD OFFPAGE_IN..2
R 2
(-14400 1050);
FORCEPROP 2 LAST $XR0 24H4> 
J 0
(-14583 1050);
DISPLAY 0.638298 (-14583 1050);
PAINT MONO (-14583 1050);
FORCEPROP 1 LAST BODY_TYPE COMMENT
J 2
(-14410 1185);
DISPLAY 0.808511 (-14410 1185);
PAINT GREEN (-14410 1185);
DISPLAY INVISIBLE (-14410 1185);
FORCEPROP 1 LAST CDS_LMAN_SYM_OUTLINE -50,50,50,-50
J 2
(-14400 1050);
DISPLAY 0.468085 (-14400 1050);
PAINT GREEN (-14400 1050);
DISPLAY INVISIBLE (-14400 1050);
FORCEPROP 2 LAST CDS_LIB cls
J 0
(-14400 1050);
DISPLAY INVISIBLE (-14400 1050);
FORCEPROP 1 LAST OFFPAGE TRUE
J 2
(-14410 1105);
DISPLAY 0.808511 (-14410 1105);
PAINT GREEN (-14410 1105);
DISPLAY INVISIBLE (-14410 1105);
FORCEPROP 2 LAST PATH I452
J 0
(-14350 1150);
DISPLAY 1.021277 (-14350 1150);
DISPLAY INVISIBLE (-14350 1150);
FORCEADD OFFPAGE_IN..2
R 2
(-14400 1600);
FORCEPROP 2 LAST $XR0 24H4> 
J 0
(-14583 1600);
DISPLAY 0.638298 (-14583 1600);
PAINT MONO (-14583 1600);
FORCEPROP 1 LAST BODY_TYPE COMMENT
J 2
(-14410 1735);
DISPLAY 0.808511 (-14410 1735);
PAINT GREEN (-14410 1735);
DISPLAY INVISIBLE (-14410 1735);
FORCEPROP 1 LAST CDS_LMAN_SYM_OUTLINE -50,50,50,-50
J 2
(-14400 1600);
DISPLAY 0.468085 (-14400 1600);
PAINT GREEN (-14400 1600);
DISPLAY INVISIBLE (-14400 1600);
FORCEPROP 2 LAST CDS_LIB cls
J 0
(-14400 1600);
DISPLAY INVISIBLE (-14400 1600);
FORCEPROP 1 LAST OFFPAGE TRUE
J 2
(-14410 1655);
DISPLAY 0.808511 (-14410 1655);
PAINT GREEN (-14410 1655);
DISPLAY INVISIBLE (-14410 1655);
FORCEPROP 2 LAST PATH I453
J 0
(-14350 1700);
DISPLAY 1.021277 (-14350 1700);
DISPLAY INVISIBLE (-14350 1700);
FORCEADD OFFPAGE_OUT..1
R 2
(-14400 1400);
FORCEPROP 2 LAST $XR0 24J4< 
J 0
(-14583 1400);
DISPLAY 0.638298 (-14583 1400);
PAINT MONO (-14583 1400);
FORCEPROP 1 LAST BODY_TYPE COMMENT
J 2
(-14410 1535);
DISPLAY 0.808511 (-14410 1535);
PAINT GREEN (-14410 1535);
DISPLAY INVISIBLE (-14410 1535);
FORCEPROP 1 LAST CDS_LMAN_SYM_OUTLINE -50,50,50,-50
J 2
(-14400 1400);
DISPLAY 0.468085 (-14400 1400);
PAINT GREEN (-14400 1400);
DISPLAY INVISIBLE (-14400 1400);
FORCEPROP 2 LAST CDS_LIB cls
J 0
(-14400 1400);
DISPLAY INVISIBLE (-14400 1400);
FORCEPROP 1 LAST OFFPAGE TRUE
J 2
(-14410 1455);
DISPLAY 0.808511 (-14410 1455);
PAINT GREEN (-14410 1455);
DISPLAY INVISIBLE (-14410 1455);
FORCEPROP 2 LAST PATH I454
J 0
(-14350 1500);
DISPLAY 1.021277 (-14350 1500);
DISPLAY INVISIBLE (-14350 1500);
FORCEADD OFFPAGE_IN..2
R 2
(-14400 1200);
FORCEPROP 2 LAST $XR0 24J4> 
J 0
(-14583 1200);
DISPLAY 0.638298 (-14583 1200);
PAINT MONO (-14583 1200);
FORCEPROP 1 LAST BODY_TYPE COMMENT
J 2
(-14410 1335);
DISPLAY 0.808511 (-14410 1335);
PAINT GREEN (-14410 1335);
DISPLAY INVISIBLE (-14410 1335);
FORCEPROP 1 LAST CDS_LMAN_SYM_OUTLINE -50,50,50,-50
J 2
(-14400 1200);
DISPLAY 0.468085 (-14400 1200);
PAINT GREEN (-14400 1200);
DISPLAY INVISIBLE (-14400 1200);
FORCEPROP 2 LAST CDS_LIB cls
J 0
(-14400 1200);
DISPLAY INVISIBLE (-14400 1200);
FORCEPROP 1 LAST OFFPAGE TRUE
J 2
(-14410 1255);
DISPLAY 0.808511 (-14410 1255);
PAINT GREEN (-14410 1255);
DISPLAY INVISIBLE (-14410 1255);
FORCEPROP 2 LAST PATH I455
J 0
(-14350 1300);
DISPLAY 1.021277 (-14350 1300);
DISPLAY INVISIBLE (-14350 1300);
FORCEADD MT25QL128ABA1ESE_SOP8..1
(-6100 550);
FORCEPROP 0 LASTPIN (-5200 50) $PN 3
J 0
(-5190 60);
DISPLAY 0.680851 (-5190 60);
PAINT MONO (-5190 60);
FORCEPROP 0 LASTPIN (-5200 -250) $PN 4
J 0
(-5190 -240);
DISPLAY 0.680851 (-5190 -240);
PAINT MONO (-5190 -240);
FORCEPROP 0 LASTPIN (-6200 450) $PN 8
J 2
(-6210 460);
DISPLAY 0.680851 (-6210 460);
PAINT MONO (-6210 460);
FORCEPROP 0 LASTPIN (-6200 50) $PN 1
J 2
(-6210 60);
DISPLAY 0.680851 (-6210 60);
PAINT MONO (-6210 60);
FORCEPROP 0 LASTPIN (-5200 -50) $PN 7
J 0
(-5190 -40);
DISPLAY 0.680851 (-5190 -40);
PAINT MONO (-5190 -40);
FORCEPROP 0 LASTPIN (-5200 150) $PN 2
J 0
(-5190 160);
DISPLAY 0.680851 (-5190 160);
PAINT MONO (-5190 160);
FORCEPROP 0 LASTPIN (-5200 250) $PN 5
J 0
(-5190 260);
DISPLAY 0.680851 (-5190 260);
PAINT MONO (-5190 260);
FORCEPROP 0 LASTPIN (-6200 250) $PN 6
J 2
(-6210 260);
DISPLAY 0.680851 (-6210 260);
PAINT MONO (-6210 260);
FORCEPROP 1 LAST $LOCATION U23
J 0
(-6100 600);
DISPLAY 1.212766 (-6100 600);
PAINT GREEN (-6100 600);
FORCEPROP 1 LAST VALUE MT25QL128ABA1ESE-0SIT
J 0
(-6100 800);
DISPLAY 1.212766 (-6100 800);
PAINT GREEN (-6100 800);
FORCEPROP 1 LAST CLS_PN G221-10224-01
J 0
(-6100 700);
DISPLAY 1.212766 (-6100 700);
PAINT GREEN (-6100 700);
FORCEPROP 0 LAST CDS_SEC 1
J 0
(-6050 950);
DISPLAY 1.021277 (-6050 950);
DISPLAY INVISIBLE (-6050 950);
FORCEPROP 0 LAST $SEC 1
J 0
(-6050 950);
DISPLAY 0.680851 (-6050 950);
PAINT MONO (-6050 950);
DISPLAY INVISIBLE (-6050 950);
FORCEPROP 0 LAST CDS_LOCATION U23
J 0
(-6050 950);
DISPLAY 1.021277 (-6050 950);
DISPLAY INVISIBLE (-6050 950);
FORCEPROP 2 LAST CDS_LIB memory
J 0
(-6100 550);
DISPLAY INVISIBLE (-6100 550);
FORCEPROP 1 LAST CDS_LMAN_SYM_OUTLINE 0,0,800,-900
J 0
(-6100 550);
DISPLAY 0.468085 (-6100 550);
PAINT GREEN (-6100 550);
DISPLAY INVISIBLE (-6100 550);
FORCEPROP 1 LAST PATH I456
J 0
(-6050 570);
DISPLAY 1.212766 (-6050 570);
PAINT GREEN (-6050 570);
DISPLAY INVISIBLE (-6050 570);
FORCEPROP 2 LASTPIN (-5200 150) SIG_NAME UN$127$MT25QL128ABA1ESESOP8$I456$DQ1
J 0
(-5190 160);
DISPLAY 0.659574 (-5190 160);
PAINT MONO (-5190 160);
DISPLAY INVISIBLE (-5190 160);
FORCEPROP 2 LASTPIN (-5200 -50) SIG_NAME UN$127$MT25QL128ABA1ESESOP8$I456$HOLD
J 0
(-5190 -40);
DISPLAY 0.659574 (-5190 -40);
PAINT MONO (-5190 -40);
DISPLAY INVISIBLE (-5190 -40);
FORCEPROP 2 LASTPIN (-5200 250) SIG_NAME UN$127$MT25QL128ABA1ESESOP8$I456$DQ0
J 0
(-5190 260);
DISPLAY 0.659574 (-5190 260);
PAINT MONO (-5190 260);
DISPLAY INVISIBLE (-5190 260);
FORCEPROP 2 LASTPIN (-5200 50) SIG_NAME UN$127$MT25QL128ABA1ESESOP8$I456$W
J 0
(-5190 60);
DISPLAY 0.659574 (-5190 60);
PAINT MONO (-5190 60);
DISPLAY INVISIBLE (-5190 60);
FORCEADD VCC..1
(-3800 850);
FORCEPROP 3 LASTPIN (-3750 800) SIG_NAME XP3R3V_FPGA\g
J 0
(-3740 810);
DISPLAY 0.659574 (-3740 810);
PAINT MONO (-3740 810);
DISPLAY INVISIBLE (-3740 810);
FORCEPROP 0 LAST VOLTAGE 3.3V
J 0
(-4050 1000);
DISPLAY 1.021277 (-4050 1000);
DISPLAY BOTH (-4050 1000);
FORCEPROP 1 LAST HDL_POWER XP3R3V_FPGA
J 1
(-3745 905);
DISPLAY 1.021277 (-3745 905);
PAINT GREEN (-3745 905);
FORCEPROP 1 LAST PATH I457
J 0
(-3765 940);
DISPLAY 0.808511 (-3765 940);
PAINT GREEN (-3765 940);
DISPLAY INVISIBLE (-3765 940);
FORCEPROP 1 LAST BODY_TYPE PLUMBING
J 0
(-3845 807);
DISPLAY 0.340426 (-3845 807);
PAINT GREEN (-3845 807);
DISPLAY INVISIBLE (-3845 807);
FORCEPROP 2 LAST CDS_LIB cls
J 0
(-3800 850);
DISPLAY INVISIBLE (-3800 850);
FORCEPROP 1 LAST CDS_LMAN_SYM_OUTLINE -250,250,250,-250
J 0
(-3800 850);
DISPLAY 0.468085 (-3800 850);
PAINT GREEN (-3800 850);
DISPLAY INVISIBLE (-3800 850);
FORCEADD OFFPAGE_BI..1
(-3000 250);
FORCEPROP 2 LAST $XR0 24H10<> 
J 0
(-2940 250);
DISPLAY 0.638298 (-2940 250);
PAINT MONO (-2940 250);
FORCEPROP 1 LAST OFFPAGE TRUE
J 0
(-2990 305);
DISPLAY 0.808511 (-2990 305);
PAINT GREEN (-2990 305);
DISPLAY INVISIBLE (-2990 305);
FORCEPROP 2 LAST CDS_LIB cls
J 0
(-3000 250);
DISPLAY INVISIBLE (-3000 250);
FORCEPROP 1 LAST CDS_LMAN_SYM_OUTLINE -50,50,50,-50
J 0
(-3000 250);
DISPLAY 0.468085 (-3000 250);
PAINT GREEN (-3000 250);
DISPLAY INVISIBLE (-3000 250);
FORCEPROP 1 LAST BODY_TYPE COMMENT
J 0
(-2990 385);
DISPLAY 0.808511 (-2990 385);
PAINT GREEN (-2990 385);
DISPLAY INVISIBLE (-2990 385);
FORCEPROP 2 LAST PATH I458
J 0
(-2900 300);
DISPLAY 1.021277 (-2900 300);
DISPLAY INVISIBLE (-2900 300);
FORCEADD OFFPAGE_BI..1
(-3000 150);
FORCEPROP 2 LAST $XR0 24J10<> 
J 0
(-2940 150);
DISPLAY 0.638298 (-2940 150);
PAINT MONO (-2940 150);
FORCEPROP 1 LAST OFFPAGE TRUE
J 0
(-2990 205);
DISPLAY 0.808511 (-2990 205);
PAINT GREEN (-2990 205);
DISPLAY INVISIBLE (-2990 205);
FORCEPROP 2 LAST CDS_LIB cls
J 0
(-3000 150);
DISPLAY INVISIBLE (-3000 150);
FORCEPROP 1 LAST CDS_LMAN_SYM_OUTLINE -50,50,50,-50
J 0
(-3000 150);
DISPLAY 0.468085 (-3000 150);
PAINT GREEN (-3000 150);
DISPLAY INVISIBLE (-3000 150);
FORCEPROP 1 LAST BODY_TYPE COMMENT
J 0
(-2990 285);
DISPLAY 0.808511 (-2990 285);
PAINT GREEN (-2990 285);
DISPLAY INVISIBLE (-2990 285);
FORCEPROP 2 LAST PATH I459
J 0
(-2900 200);
DISPLAY 1.021277 (-2900 200);
DISPLAY INVISIBLE (-2900 200);
FORCEADD OFFPAGE_BI..1
(-3000 50);
FORCEPROP 2 LAST $XR0 24K10<> 
J 0
(-2940 50);
DISPLAY 0.638298 (-2940 50);
PAINT MONO (-2940 50);
FORCEPROP 1 LAST BODY_TYPE COMMENT
J 0
(-2990 185);
DISPLAY 0.808511 (-2990 185);
PAINT GREEN (-2990 185);
DISPLAY INVISIBLE (-2990 185);
FORCEPROP 1 LAST CDS_LMAN_SYM_OUTLINE -50,50,50,-50
J 0
(-3000 50);
DISPLAY 0.468085 (-3000 50);
PAINT GREEN (-3000 50);
DISPLAY INVISIBLE (-3000 50);
FORCEPROP 2 LAST CDS_LIB cls
J 0
(-3000 50);
DISPLAY INVISIBLE (-3000 50);
FORCEPROP 1 LAST OFFPAGE TRUE
J 0
(-2990 105);
DISPLAY 0.808511 (-2990 105);
PAINT GREEN (-2990 105);
DISPLAY INVISIBLE (-2990 105);
FORCEPROP 2 LAST PATH I460
J 0
(-2900 100);
DISPLAY 1.021277 (-2900 100);
DISPLAY INVISIBLE (-2900 100);
FORCEADD OFFPAGE_BI..1
(-3000 -50);
FORCEPROP 2 LAST $XR0 24L10<> 
J 0
(-2940 -50);
DISPLAY 0.638298 (-2940 -50);
PAINT MONO (-2940 -50);
FORCEPROP 2 LAST CDS_LIB cls
J 0
(-3000 -50);
DISPLAY INVISIBLE (-3000 -50);
FORCEPROP 1 LAST CDS_LMAN_SYM_OUTLINE -50,50,50,-50
J 0
(-3000 -50);
DISPLAY 0.468085 (-3000 -50);
PAINT GREEN (-3000 -50);
DISPLAY INVISIBLE (-3000 -50);
FORCEPROP 1 LAST BODY_TYPE COMMENT
J 0
(-2990 85);
DISPLAY 0.808511 (-2990 85);
PAINT GREEN (-2990 85);
DISPLAY INVISIBLE (-2990 85);
FORCEPROP 1 LAST OFFPAGE TRUE
J 0
(-2990 5);
DISPLAY 0.808511 (-2990 5);
PAINT GREEN (-2990 5);
DISPLAY INVISIBLE (-2990 5);
FORCEPROP 2 LAST PATH I461
J 0
(-2900 0);
DISPLAY 1.021277 (-2900 0);
DISPLAY INVISIBLE (-2900 0);
FORCEADD RESISTOR..1
(-4500 700);
FORCEPROP 0 LASTPIN (-4350 700) $PN 2
J 0
(-4340 710);
DISPLAY 0.680851 (-4340 710);
PAINT MONO (-4340 710);
FORCEPROP 0 LASTPIN (-4600 700) $PN 1
J 2
(-4610 710);
DISPLAY 0.680851 (-4610 710);
PAINT MONO (-4610 710);
FORCEPROP 1 LAST $LOCATION R199
J 2
(-4650 700);
DISPLAY 1.212766 (-4650 700);
PAINT GREEN (-4650 700);
FORCEPROP 1 LAST VALUE 4.7KOHM
J 0
(-4261 705);
DISPLAY 1.212766 (-4261 705);
PAINT GREEN (-4261 705);
FORCEPROP 0 LAST PACKAGE 0402
J 0
(-4550 650);
DISPLAY 0.638298 (-4550 650);
FORCEPROP 0 LAST CDS_SEC 1
J 0
(-4250 800);
DISPLAY 1.021277 (-4250 800);
DISPLAY INVISIBLE (-4250 800);
FORCEPROP 0 LAST $SEC 1
J 0
(-4250 800);
DISPLAY 0.680851 (-4250 800);
PAINT MONO (-4250 800);
DISPLAY INVISIBLE (-4250 800);
FORCEPROP 0 LAST CDS_LOCATION R199
J 0
(-4250 800);
DISPLAY 1.021277 (-4250 800);
DISPLAY INVISIBLE (-4250 800);
FORCEPROP 1 LAST PATH I462
J 0
(-4697 805);
DISPLAY 1.212766 (-4697 805);
PAINT GREEN (-4697 805);
DISPLAY INVISIBLE (-4697 805);
FORCEPROP 1 LAST TOLERANCE 1%
J 0
(-4697 955);
DISPLAY 1.212766 (-4697 955);
PAINT GREEN (-4697 955);
DISPLAY INVISIBLE (-4697 955);
FORCEPROP 1 LAST CLS_PN G155-14701-01
J 0
(-4636 900);
DISPLAY 1.212766 (-4636 900);
PAINT GREEN (-4636 900);
DISPLAY INVISIBLE (-4636 900);
FORCEPROP 1 LAST CDS_LMAN_SYM_OUTLINE -50,50,100,-50
J 0
(-4500 700);
DISPLAY 0.468085 (-4500 700);
PAINT GREEN (-4500 700);
DISPLAY INVISIBLE (-4500 700);
FORCEPROP 2 LAST CDS_LIB passive
J 0
(-4500 700);
DISPLAY INVISIBLE (-4500 700);
FORCEADD RESISTOR..1
(-4500 500);
FORCEPROP 0 LASTPIN (-4350 500) $PN 2
J 0
(-4340 510);
DISPLAY 0.680851 (-4340 510);
PAINT MONO (-4340 510);
FORCEPROP 0 LASTPIN (-4600 500) $PN 1
J 2
(-4610 510);
DISPLAY 0.680851 (-4610 510);
PAINT MONO (-4610 510);
FORCEPROP 1 LAST LOCATION R201
J 2
(-4650 500);
DISPLAY 1.212766 (-4650 500);
PAINT GREEN (-4650 500);
FORCEPROP 1 LAST VALUE 4.7KOHM
J 0
(-4261 505);
DISPLAY 1.212766 (-4261 505);
PAINT GREEN (-4261 505);
FORCEPROP 0 LAST PACKAGE 0402
J 0
(-4550 450);
DISPLAY 0.638298 (-4550 450);
FORCEPROP 0 LAST CDS_SEC 1
J 0
(-4250 600);
DISPLAY 1.021277 (-4250 600);
DISPLAY INVISIBLE (-4250 600);
FORCEPROP 0 LAST $SEC 1
J 0
(-4250 600);
DISPLAY 0.680851 (-4250 600);
PAINT MONO (-4250 600);
DISPLAY INVISIBLE (-4250 600);
FORCEPROP 1 LAST PATH I463
J 0
(-4697 605);
DISPLAY 1.212766 (-4697 605);
PAINT GREEN (-4697 605);
DISPLAY INVISIBLE (-4697 605);
FORCEPROP 1 LAST TOLERANCE 1%
J 0
(-4697 755);
DISPLAY 1.212766 (-4697 755);
PAINT GREEN (-4697 755);
DISPLAY INVISIBLE (-4697 755);
FORCEPROP 1 LAST CLS_PN G155-14701-01
J 0
(-4636 700);
DISPLAY 1.212766 (-4636 700);
PAINT GREEN (-4636 700);
DISPLAY INVISIBLE (-4636 700);
FORCEPROP 1 LAST CDS_LMAN_SYM_OUTLINE -50,50,100,-50
J 0
(-4500 500);
DISPLAY 0.468085 (-4500 500);
PAINT GREEN (-4500 500);
DISPLAY INVISIBLE (-4500 500);
FORCEPROP 2 LAST CDS_LIB passive
J 0
(-4500 500);
DISPLAY INVISIBLE (-4500 500);
FORCEADD RESISTOR..1
(-4500 400);
FORCEPROP 0 LASTPIN (-4350 400) $PN 2
J 0
(-4340 410);
DISPLAY 0.680851 (-4340 410);
PAINT MONO (-4340 410);
FORCEPROP 0 LASTPIN (-4600 400) $PN 1
J 2
(-4610 410);
DISPLAY 0.680851 (-4610 410);
PAINT MONO (-4610 410);
FORCEPROP 1 LAST LOCATION R202
J 2
(-4650 400);
DISPLAY 1.212766 (-4650 400);
PAINT GREEN (-4650 400);
FORCEPROP 1 LAST VALUE 4.7KOHM
J 0
(-4261 405);
DISPLAY 1.212766 (-4261 405);
PAINT GREEN (-4261 405);
FORCEPROP 0 LAST PACKAGE 0402
J 0
(-4550 350);
DISPLAY 0.638298 (-4550 350);
FORCEPROP 0 LAST CDS_SEC 1
J 0
(-4250 500);
DISPLAY 1.021277 (-4250 500);
DISPLAY INVISIBLE (-4250 500);
FORCEPROP 0 LAST $SEC 1
J 0
(-4250 500);
DISPLAY 0.680851 (-4250 500);
PAINT MONO (-4250 500);
DISPLAY INVISIBLE (-4250 500);
FORCEPROP 1 LAST PATH I464
J 0
(-4697 505);
DISPLAY 1.212766 (-4697 505);
PAINT GREEN (-4697 505);
DISPLAY INVISIBLE (-4697 505);
FORCEPROP 1 LAST TOLERANCE 1%
J 0
(-4697 655);
DISPLAY 1.212766 (-4697 655);
PAINT GREEN (-4697 655);
DISPLAY INVISIBLE (-4697 655);
FORCEPROP 2 LAST CDS_LIB passive
J 0
(-4500 400);
DISPLAY INVISIBLE (-4500 400);
FORCEPROP 1 LAST CDS_LMAN_SYM_OUTLINE -50,50,100,-50
J 0
(-4500 400);
DISPLAY 0.468085 (-4500 400);
PAINT GREEN (-4500 400);
DISPLAY INVISIBLE (-4500 400);
FORCEPROP 1 LAST CLS_PN G155-14701-01
J 0
(-4636 600);
DISPLAY 1.212766 (-4636 600);
PAINT GREEN (-4636 600);
DISPLAY INVISIBLE (-4636 600);
FORCEADD RESISTOR..1
(-4500 600);
FORCEPROP 0 LASTPIN (-4350 600) $PN 2
J 0
(-4340 610);
DISPLAY 0.680851 (-4340 610);
PAINT MONO (-4340 610);
FORCEPROP 0 LASTPIN (-4600 600) $PN 1
J 2
(-4610 610);
DISPLAY 0.680851 (-4610 610);
PAINT MONO (-4610 610);
FORCEPROP 1 LAST LOCATION R200
J 2
(-4650 600);
DISPLAY 1.212766 (-4650 600);
PAINT GREEN (-4650 600);
FORCEPROP 1 LAST VALUE 4.7KOHM
J 0
(-4261 605);
DISPLAY 1.212766 (-4261 605);
PAINT GREEN (-4261 605);
FORCEPROP 0 LAST PACKAGE 0402
J 0
(-4550 550);
DISPLAY 0.638298 (-4550 550);
FORCEPROP 0 LAST CDS_SEC 1
J 0
(-4250 700);
DISPLAY 1.021277 (-4250 700);
DISPLAY INVISIBLE (-4250 700);
FORCEPROP 0 LAST $SEC 1
J 0
(-4250 700);
DISPLAY 0.680851 (-4250 700);
PAINT MONO (-4250 700);
DISPLAY INVISIBLE (-4250 700);
FORCEPROP 1 LAST PATH I465
J 0
(-4697 705);
DISPLAY 1.212766 (-4697 705);
PAINT GREEN (-4697 705);
DISPLAY INVISIBLE (-4697 705);
FORCEPROP 1 LAST TOLERANCE 1%
J 0
(-4697 855);
DISPLAY 1.212766 (-4697 855);
PAINT GREEN (-4697 855);
DISPLAY INVISIBLE (-4697 855);
FORCEPROP 1 LAST CLS_PN G155-14701-01
J 0
(-4636 800);
DISPLAY 1.212766 (-4636 800);
PAINT GREEN (-4636 800);
DISPLAY INVISIBLE (-4636 800);
FORCEPROP 1 LAST CDS_LMAN_SYM_OUTLINE -50,50,100,-50
J 0
(-4500 600);
DISPLAY 0.468085 (-4500 600);
PAINT GREEN (-4500 600);
DISPLAY INVISIBLE (-4500 600);
FORCEPROP 2 LAST CDS_LIB passive
J 0
(-4500 600);
DISPLAY INVISIBLE (-4500 600);
FORCEADD RESISTOR..1
(-4500 150);
FORCEPROP 0 LASTPIN (-4350 150) $PN 2
J 0
(-4340 160);
DISPLAY 0.680851 (-4340 160);
PAINT MONO (-4340 160);
FORCEPROP 0 LASTPIN (-4600 150) $PN 1
J 2
(-4610 160);
DISPLAY 0.680851 (-4610 160);
PAINT MONO (-4610 160);
FORCEPROP 1 LAST LOCATION R204
J 2
(-4650 150);
DISPLAY 1.212766 (-4650 150);
PAINT GREEN (-4650 150);
FORCEPROP 1 LAST VALUE 33OHM
J 0
(-4261 155);
DISPLAY 1.212766 (-4261 155);
PAINT GREEN (-4261 155);
FORCEPROP 0 LAST PACKAGE 0402
J 0
(-4550 100);
DISPLAY 0.638298 (-4550 100);
FORCEPROP 0 LAST CDS_SEC 1
J 0
(-4250 250);
DISPLAY 1.021277 (-4250 250);
DISPLAY INVISIBLE (-4250 250);
FORCEPROP 0 LAST $SEC 1
J 0
(-4250 250);
DISPLAY 0.680851 (-4250 250);
PAINT MONO (-4250 250);
DISPLAY INVISIBLE (-4250 250);
FORCEPROP 1 LAST PATH I466
J 0
(-4697 255);
DISPLAY 1.212766 (-4697 255);
PAINT GREEN (-4697 255);
DISPLAY INVISIBLE (-4697 255);
FORCEPROP 1 LAST TOLERANCE 1%
J 0
(-4697 405);
DISPLAY 1.212766 (-4697 405);
PAINT GREEN (-4697 405);
DISPLAY INVISIBLE (-4697 405);
FORCEPROP 2 LAST CDS_LIB passive
J 0
(-4500 150);
DISPLAY INVISIBLE (-4500 150);
FORCEPROP 1 LAST CDS_LMAN_SYM_OUTLINE -50,50,100,-50
J 0
(-4500 150);
DISPLAY 0.468085 (-4500 150);
PAINT GREEN (-4500 150);
DISPLAY INVISIBLE (-4500 150);
FORCEPROP 1 LAST CLS_PN G155-133R0-01
J 0
(-4636 350);
DISPLAY 1.212766 (-4636 350);
PAINT GREEN (-4636 350);
DISPLAY INVISIBLE (-4636 350);
FORCEADD RESISTOR..1
(-4500 250);
FORCEPROP 0 LASTPIN (-4350 250) $PN 2
J 0
(-4340 260);
DISPLAY 0.680851 (-4340 260);
PAINT MONO (-4340 260);
FORCEPROP 0 LASTPIN (-4600 250) $PN 1
J 2
(-4610 260);
DISPLAY 0.680851 (-4610 260);
PAINT MONO (-4610 260);
FORCEPROP 1 LAST $LOCATION R203
J 2
(-4650 250);
DISPLAY 1.212766 (-4650 250);
PAINT GREEN (-4650 250);
FORCEPROP 0 LAST PACKAGE 0402
J 0
(-4550 200);
DISPLAY 0.638298 (-4550 200);
FORCEPROP 1 LAST VALUE 33OHM
J 0
(-4261 255);
DISPLAY 1.212766 (-4261 255);
PAINT GREEN (-4261 255);
FORCEPROP 0 LAST CDS_SEC 1
J 0
(-4250 350);
DISPLAY 1.021277 (-4250 350);
DISPLAY INVISIBLE (-4250 350);
FORCEPROP 0 LAST $SEC 1
J 0
(-4250 350);
DISPLAY 0.680851 (-4250 350);
PAINT MONO (-4250 350);
DISPLAY INVISIBLE (-4250 350);
FORCEPROP 0 LAST CDS_LOCATION R203
J 0
(-4250 350);
DISPLAY 1.021277 (-4250 350);
DISPLAY INVISIBLE (-4250 350);
FORCEPROP 1 LAST PATH I467
J 0
(-4697 355);
DISPLAY 1.212766 (-4697 355);
PAINT GREEN (-4697 355);
DISPLAY INVISIBLE (-4697 355);
FORCEPROP 1 LAST TOLERANCE 1%
J 0
(-4697 505);
DISPLAY 1.212766 (-4697 505);
PAINT GREEN (-4697 505);
DISPLAY INVISIBLE (-4697 505);
FORCEPROP 1 LAST CLS_PN G155-133R0-01
J 0
(-4636 450);
DISPLAY 1.212766 (-4636 450);
PAINT GREEN (-4636 450);
DISPLAY INVISIBLE (-4636 450);
FORCEPROP 1 LAST CDS_LMAN_SYM_OUTLINE -50,50,100,-50
J 0
(-4500 250);
DISPLAY 0.468085 (-4500 250);
PAINT GREEN (-4500 250);
DISPLAY INVISIBLE (-4500 250);
FORCEPROP 2 LAST CDS_LIB passive
J 0
(-4500 250);
DISPLAY INVISIBLE (-4500 250);
FORCEADD RESISTOR..1
(-4500 50);
FORCEPROP 0 LASTPIN (-4350 50) $PN 2
J 0
(-4340 60);
DISPLAY 0.680851 (-4340 60);
PAINT MONO (-4340 60);
FORCEPROP 0 LASTPIN (-4600 50) $PN 1
J 2
(-4610 60);
DISPLAY 0.680851 (-4610 60);
PAINT MONO (-4610 60);
FORCEPROP 1 LAST LOCATION R205
J 2
(-4650 50);
DISPLAY 1.212766 (-4650 50);
PAINT GREEN (-4650 50);
FORCEPROP 1 LAST VALUE 33OHM
J 0
(-4261 55);
DISPLAY 1.212766 (-4261 55);
PAINT GREEN (-4261 55);
FORCEPROP 0 LAST PACKAGE 0402
J 0
(-4550 0);
DISPLAY 0.638298 (-4550 0);
FORCEPROP 0 LAST CDS_SEC 1
J 0
(-4250 150);
DISPLAY 1.021277 (-4250 150);
DISPLAY INVISIBLE (-4250 150);
FORCEPROP 0 LAST $SEC 1
J 0
(-4250 150);
DISPLAY 0.680851 (-4250 150);
PAINT MONO (-4250 150);
DISPLAY INVISIBLE (-4250 150);
FORCEPROP 1 LAST PATH I468
J 0
(-4697 155);
DISPLAY 1.212766 (-4697 155);
PAINT GREEN (-4697 155);
DISPLAY INVISIBLE (-4697 155);
FORCEPROP 1 LAST TOLERANCE 1%
J 0
(-4697 305);
DISPLAY 1.212766 (-4697 305);
PAINT GREEN (-4697 305);
DISPLAY INVISIBLE (-4697 305);
FORCEPROP 2 LAST CDS_LIB passive
J 0
(-4500 50);
DISPLAY INVISIBLE (-4500 50);
FORCEPROP 1 LAST CDS_LMAN_SYM_OUTLINE -50,50,100,-50
J 0
(-4500 50);
DISPLAY 0.468085 (-4500 50);
PAINT GREEN (-4500 50);
DISPLAY INVISIBLE (-4500 50);
FORCEPROP 1 LAST CLS_PN G155-133R0-01
J 0
(-4636 250);
DISPLAY 1.212766 (-4636 250);
PAINT GREEN (-4636 250);
DISPLAY INVISIBLE (-4636 250);
FORCEADD RESISTOR..1
(-4500 -50);
FORCEPROP 0 LASTPIN (-4350 -50) $PN 2
J 0
(-4340 -40);
DISPLAY 0.680851 (-4340 -40);
PAINT MONO (-4340 -40);
FORCEPROP 0 LASTPIN (-4600 -50) $PN 1
J 2
(-4610 -40);
DISPLAY 0.680851 (-4610 -40);
PAINT MONO (-4610 -40);
FORCEPROP 1 LAST LOCATION R206
J 2
(-4650 -50);
DISPLAY 1.212766 (-4650 -50);
PAINT GREEN (-4650 -50);
FORCEPROP 1 LAST VALUE 33OHM
J 0
(-4261 -45);
DISPLAY 1.212766 (-4261 -45);
PAINT GREEN (-4261 -45);
FORCEPROP 0 LAST PACKAGE 0402
J 0
(-4550 -100);
DISPLAY 0.638298 (-4550 -100);
FORCEPROP 0 LAST CDS_SEC 1
J 0
(-4250 50);
DISPLAY 1.021277 (-4250 50);
DISPLAY INVISIBLE (-4250 50);
FORCEPROP 0 LAST $SEC 1
J 0
(-4250 50);
DISPLAY 0.680851 (-4250 50);
PAINT MONO (-4250 50);
DISPLAY INVISIBLE (-4250 50);
FORCEPROP 1 LAST PATH I469
J 0
(-4697 55);
DISPLAY 1.212766 (-4697 55);
PAINT GREEN (-4697 55);
DISPLAY INVISIBLE (-4697 55);
FORCEPROP 1 LAST TOLERANCE 1%
J 0
(-4697 205);
DISPLAY 1.212766 (-4697 205);
PAINT GREEN (-4697 205);
DISPLAY INVISIBLE (-4697 205);
FORCEPROP 1 LAST CLS_PN G155-133R0-01
J 0
(-4636 150);
DISPLAY 1.212766 (-4636 150);
PAINT GREEN (-4636 150);
DISPLAY INVISIBLE (-4636 150);
FORCEPROP 1 LAST CDS_LMAN_SYM_OUTLINE -50,50,100,-50
J 0
(-4500 -50);
DISPLAY 0.468085 (-4500 -50);
PAINT GREEN (-4500 -50);
DISPLAY INVISIBLE (-4500 -50);
FORCEPROP 2 LAST CDS_LIB passive
J 0
(-4500 -50);
DISPLAY INVISIBLE (-4500 -50);
FORCEADD RESISTOR..2
(-6400 -200);
FORCEPROP 0 LASTPIN (-6400 -350) $PN 2
R 1
J 2
(-6410 -360);
DISPLAY 0.680851 (-6410 -360);
PAINT MONO (-6410 -360);
FORCEPROP 0 LASTPIN (-6400 -100) $PN 1
R 1
J 0
(-6410 -90);
DISPLAY 0.680851 (-6410 -90);
PAINT MONO (-6410 -90);
FORCEPROP 1 LAST $LOCATION R192
J 0
(-6800 -300);
DISPLAY 1.212766 (-6800 -300);
PAINT GREEN (-6800 -300);
FORCEPROP 1 LAST VALUE 4.7KOHM
J 0
(-6800 -200);
DISPLAY 0.978723 (-6800 -200);
PAINT GREEN (-6800 -200);
FORCEPROP 0 LAST PACKAGE 0402
J 0
(-6800 -400);
DISPLAY 1.021277 (-6800 -400);
FORCEPROP 0 LAST CDS_SEC 1
J 0
(-6800 -150);
DISPLAY 1.021277 (-6800 -150);
DISPLAY INVISIBLE (-6800 -150);
FORCEPROP 0 LAST $SEC 1
J 0
(-6800 -150);
DISPLAY 0.680851 (-6800 -150);
PAINT MONO (-6800 -150);
DISPLAY INVISIBLE (-6800 -150);
FORCEPROP 0 LAST CDS_LOCATION R192
J 0
(-6800 -150);
DISPLAY 1.021277 (-6800 -150);
DISPLAY INVISIBLE (-6800 -150);
FORCEPROP 1 LAST CDS_LMAN_SYM_OUTLINE -50,50,50,-100
J 0
(-6400 -200);
DISPLAY 0.468085 (-6400 -200);
PAINT GREEN (-6400 -200);
DISPLAY INVISIBLE (-6400 -200);
FORCEPROP 2 LAST CDS_LIB passive
J 0
(-6400 -200);
DISPLAY INVISIBLE (-6400 -200);
FORCEPROP 1 LAST CLS_PN G155-14701-01
J 0
(-6536 0);
DISPLAY 1.212766 (-6536 0);
PAINT GREEN (-6536 0);
DISPLAY INVISIBLE (-6536 0);
FORCEPROP 1 LAST TOLERANCE 1%
J 0
(-6597 55);
DISPLAY 1.212766 (-6597 55);
PAINT GREEN (-6597 55);
DISPLAY INVISIBLE (-6597 55);
FORCEPROP 1 LAST PATH I470
J 0
(-6597 -95);
DISPLAY 1.212766 (-6597 -95);
PAINT GREEN (-6597 -95);
DISPLAY INVISIBLE (-6597 -95);
FORCEADD RESISTOR..2
R 2
(-6500 500);
FORCEPROP 0 LASTPIN (-6500 350) $PN 2
R 3
J 0
(-6460 360);
DISPLAY 0.680851 (-6460 360);
PAINT MONO (-6460 360);
FORCEPROP 0 LASTPIN (-6500 600) $PN 1
R 3
J 2
(-6460 560);
DISPLAY 0.680851 (-6460 560);
PAINT MONO (-6460 560);
FORCEPROP 1 LAST $LOCATION R191
J 0
(-6750 450);
DISPLAY 1.212766 (-6750 450);
PAINT GREEN (-6750 450);
FORCEPROP 1 LAST VALUE 4.7KOHM
J 0
(-6850 350);
DISPLAY 0.978723 (-6850 350);
PAINT GREEN (-6850 350);
FORCEPROP 0 LAST PACKAGE 0402
J 0
(-6750 550);
DISPLAY 1.021277 (-6750 550);
FORCEPROP 0 LAST CDS_SEC 1
J 2
(-6550 550);
DISPLAY 1.021277 (-6550 550);
DISPLAY INVISIBLE (-6550 550);
FORCEPROP 0 LAST $SEC 1
J 2
(-6550 550);
DISPLAY 0.680851 (-6550 550);
PAINT MONO (-6550 550);
DISPLAY INVISIBLE (-6550 550);
FORCEPROP 0 LAST CDS_LOCATION R191
J 2
(-6550 550);
DISPLAY 1.021277 (-6550 550);
DISPLAY INVISIBLE (-6550 550);
FORCEPROP 1 LAST TOLERANCE 1%
J 2
(-6303 755);
DISPLAY 1.212766 (-6303 755);
PAINT GREEN (-6303 755);
DISPLAY INVISIBLE (-6303 755);
FORCEPROP 1 LAST CLS_PN G155-14701-01
J 2
(-6364 700);
DISPLAY 1.212766 (-6364 700);
PAINT GREEN (-6364 700);
DISPLAY INVISIBLE (-6364 700);
FORCEPROP 1 LAST CDS_LMAN_SYM_OUTLINE -50,50,50,-100
J 2
(-6500 500);
DISPLAY 0.468085 (-6500 500);
PAINT GREEN (-6500 500);
DISPLAY INVISIBLE (-6500 500);
FORCEPROP 2 LAST CDS_LIB passive
J 2
(-6500 500);
DISPLAY INVISIBLE (-6500 500);
FORCEPROP 1 LAST PATH I471
J 2
(-6303 605);
DISPLAY 1.212766 (-6303 605);
PAINT GREEN (-6303 605);
DISPLAY INVISIBLE (-6303 605);
FORCEADD CAPACITOR..2
(-7000 900);
FORCEPROP 0 LASTPIN (-7000 750) $PN 2
R 1
J 2
(-7010 740);
DISPLAY 0.680851 (-7010 740);
PAINT MONO (-7010 740);
FORCEPROP 0 LASTPIN (-7000 1000) $PN 1
R 1
J 0
(-7010 1010);
DISPLAY 0.680851 (-7010 1010);
PAINT MONO (-7010 1010);
FORCEPROP 1 LAST $LOCATION C199
J 0
(-6900 750);
DISPLAY 1.212766 (-6900 750);
PAINT GREEN (-6900 750);
FORCEPROP 0 LAST VOLTAGE 10V
J 0
(-6900 950);
DISPLAY 1.021277 (-6900 950);
FORCEPROP 0 LAST PACKAGE 0402
J 0
(-6900 1050);
DISPLAY 1.021277 (-6900 1050);
FORCEPROP 1 LAST VALUE 0.1UF
J 0
(-6900 850);
DISPLAY 1.212766 (-6900 850);
PAINT GREEN (-6900 850);
FORCEPROP 0 LAST CDS_SEC 1
J 0
(-6950 1100);
DISPLAY 1.021277 (-6950 1100);
DISPLAY INVISIBLE (-6950 1100);
FORCEPROP 0 LAST $SEC 1
J 0
(-6950 1100);
DISPLAY 0.680851 (-6950 1100);
PAINT MONO (-6950 1100);
DISPLAY INVISIBLE (-6950 1100);
FORCEPROP 0 LAST CDS_LOCATION C199
J 0
(-6950 1100);
DISPLAY 1.021277 (-6950 1100);
DISPLAY INVISIBLE (-6950 1100);
FORCEPROP 1 LAST CDS_LMAN_SYM_OUTLINE -50,0,50,-50
J 0
(-7000 900);
DISPLAY 0.468085 (-7000 900);
PAINT GREEN (-7000 900);
DISPLAY INVISIBLE (-7000 900);
FORCEPROP 2 LAST CDS_LIB passive
J 0
(-7000 900);
DISPLAY INVISIBLE (-7000 900);
FORCEPROP 1 LAST CLS_PN G105-0B104-CK
J 0
(-7100 950);
DISPLAY 1.212766 (-7100 950);
PAINT GREEN (-7100 950);
DISPLAY INVISIBLE (-7100 950);
FORCEPROP 1 LAST TOLERANCE 10%
J 0
(-7150 1000);
DISPLAY 1.212766 (-7150 1000);
PAINT GREEN (-7150 1000);
DISPLAY INVISIBLE (-7150 1000);
FORCEPROP 1 LAST PATH I472
J 0
(-7100 950);
DISPLAY 1.212766 (-7100 950);
PAINT GREEN (-7100 950);
DISPLAY INVISIBLE (-7100 950);
FORCEADD CAPACITOR..2
(-7600 900);
FORCEPROP 0 LASTPIN (-7600 750) $PN 2
R 1
J 2
(-7610 740);
DISPLAY 0.680851 (-7610 740);
PAINT MONO (-7610 740);
FORCEPROP 0 LASTPIN (-7600 1000) $PN 1
R 1
J 0
(-7610 1010);
DISPLAY 0.680851 (-7610 1010);
PAINT MONO (-7610 1010);
FORCEPROP 1 LAST $LOCATION C198
J 0
(-7500 750);
DISPLAY 1.212766 (-7500 750);
PAINT GREEN (-7500 750);
FORCEPROP 1 LAST VALUE 4.7UF
J 0
(-7500 850);
DISPLAY 1.212766 (-7500 850);
PAINT GREEN (-7500 850);
FORCEPROP 0 LAST VOLTAGE 6.3V
J 0
(-7500 950);
DISPLAY 1.021277 (-7500 950);
FORCEPROP 0 LAST PACKAGE 0402
J 0
(-7500 1050);
DISPLAY 1.021277 (-7500 1050);
FORCEPROP 0 LAST CDS_SEC 1
J 0
(-7550 1100);
DISPLAY 1.021277 (-7550 1100);
DISPLAY INVISIBLE (-7550 1100);
FORCEPROP 0 LAST $SEC 1
J 0
(-7550 1100);
DISPLAY 0.680851 (-7550 1100);
PAINT MONO (-7550 1100);
DISPLAY INVISIBLE (-7550 1100);
FORCEPROP 0 LAST CDS_LOCATION C198
J 0
(-7550 1100);
DISPLAY 1.021277 (-7550 1100);
DISPLAY INVISIBLE (-7550 1100);
FORCEPROP 1 LAST PATH I473
J 0
(-7700 950);
DISPLAY 1.212766 (-7700 950);
PAINT GREEN (-7700 950);
DISPLAY INVISIBLE (-7700 950);
FORCEPROP 1 LAST TOLERANCE 20%
J 0
(-7750 1000);
DISPLAY 1.212766 (-7750 1000);
PAINT GREEN (-7750 1000);
DISPLAY INVISIBLE (-7750 1000);
FORCEPROP 1 LAST CLS_PN G105-0F475-BM
J 0
(-7700 950);
DISPLAY 1.212766 (-7700 950);
PAINT GREEN (-7700 950);
DISPLAY INVISIBLE (-7700 950);
FORCEPROP 1 LAST CDS_LMAN_SYM_OUTLINE -50,0,50,-50
J 0
(-7600 900);
DISPLAY 0.468085 (-7600 900);
PAINT GREEN (-7600 900);
DISPLAY INVISIBLE (-7600 900);
FORCEPROP 2 LAST CDS_LIB passive
J 0
(-7600 900);
DISPLAY INVISIBLE (-7600 900);
FORCEADD VCC..1
(-7650 1250);
FORCEPROP 3 LASTPIN (-7600 1200) SIG_NAME XP3R3V_FPGA\g
J 0
(-7590 1210);
DISPLAY 0.659574 (-7590 1210);
PAINT MONO (-7590 1210);
DISPLAY INVISIBLE (-7590 1210);
FORCEPROP 0 LAST VOLTAGE 3.3V
J 0
(-7900 1400);
DISPLAY 1.021277 (-7900 1400);
DISPLAY BOTH (-7900 1400);
FORCEPROP 1 LAST HDL_POWER XP3R3V_FPGA
J 1
(-7595 1305);
DISPLAY 1.021277 (-7595 1305);
PAINT GREEN (-7595 1305);
FORCEPROP 1 LAST PATH I474
J 0
(-7615 1340);
DISPLAY 0.808511 (-7615 1340);
PAINT GREEN (-7615 1340);
DISPLAY INVISIBLE (-7615 1340);
FORCEPROP 1 LAST BODY_TYPE PLUMBING
J 0
(-7695 1207);
DISPLAY 0.340426 (-7695 1207);
PAINT GREEN (-7695 1207);
DISPLAY INVISIBLE (-7695 1207);
FORCEPROP 1 LAST CDS_LMAN_SYM_OUTLINE -250,250,250,-250
J 0
(-7650 1250);
DISPLAY 0.468085 (-7650 1250);
PAINT GREEN (-7650 1250);
DISPLAY INVISIBLE (-7650 1250);
FORCEPROP 2 LAST CDS_LIB cls
J 0
(-7650 1250);
DISPLAY INVISIBLE (-7650 1250);
FORCEADD OFFPAGE_IN..2
R 2
(-7750 250);
FORCEPROP 2 LAST $XR0 24H10> 
J 0
(-7964 250);
DISPLAY 0.638298 (-7964 250);
PAINT MONO (-7964 250);
FORCEPROP 2 LAST PATH I475
J 0
(-7950 300);
DISPLAY 1.021277 (-7950 300);
DISPLAY INVISIBLE (-7950 300);
FORCEPROP 1 LAST OFFPAGE TRUE
J 2
(-7760 305);
DISPLAY 0.808511 (-7760 305);
PAINT GREEN (-7760 305);
DISPLAY INVISIBLE (-7760 305);
FORCEPROP 1 LAST BODY_TYPE COMMENT
J 2
(-7760 385);
DISPLAY 0.808511 (-7760 385);
PAINT GREEN (-7760 385);
DISPLAY INVISIBLE (-7760 385);
FORCEPROP 1 LAST CDS_LMAN_SYM_OUTLINE -50,50,50,-50
J 2
(-7750 250);
DISPLAY 0.468085 (-7750 250);
PAINT GREEN (-7750 250);
DISPLAY INVISIBLE (-7750 250);
FORCEPROP 2 LAST CDS_LIB cls
J 2
(-7750 250);
DISPLAY INVISIBLE (-7750 250);
FORCEADD OFFPAGE_IN..2
R 2
(-7750 50);
FORCEPROP 2 LAST $XR0 24J10> 
J 0
(-7964 50);
DISPLAY 0.638298 (-7964 50);
PAINT MONO (-7964 50);
FORCEPROP 2 LAST PATH I476
J 0
(-7950 100);
DISPLAY 1.021277 (-7950 100);
DISPLAY INVISIBLE (-7950 100);
FORCEPROP 1 LAST OFFPAGE TRUE
J 2
(-7760 105);
DISPLAY 0.808511 (-7760 105);
PAINT GREEN (-7760 105);
DISPLAY INVISIBLE (-7760 105);
FORCEPROP 2 LAST CDS_LIB cls
J 0
(-7750 50);
DISPLAY INVISIBLE (-7750 50);
FORCEPROP 1 LAST CDS_LMAN_SYM_OUTLINE -50,50,50,-50
J 2
(-7750 50);
DISPLAY 0.468085 (-7750 50);
PAINT GREEN (-7750 50);
DISPLAY INVISIBLE (-7750 50);
FORCEPROP 1 LAST BODY_TYPE COMMENT
J 2
(-7760 185);
DISPLAY 0.808511 (-7760 185);
PAINT GREEN (-7760 185);
DISPLAY INVISIBLE (-7760 185);
FORCEADD GND_SG..1
(-7650 500);
FORCEPROP 3 LASTPIN (-7600 550) SIG_NAME SG\g
J 0
(-7590 560);
DISPLAY 0.659574 (-7590 560);
PAINT MONO (-7590 560);
DISPLAY INVISIBLE (-7590 560);
FORCEPROP 1 LAST HDL_POWER SG
J 1
(-7595 405);
DISPLAY 0.808511 (-7595 405);
PAINT GREEN (-7595 405);
FORCEPROP 1 LAST PATH I477
J 0
(-7615 500);
DISPLAY 0.808511 (-7615 500);
PAINT GREEN (-7615 500);
DISPLAY INVISIBLE (-7615 500);
FORCEPROP 1 LAST CDS_LMAN_SYM_OUTLINE 0,0,100,-50
J 0
(-7650 500);
DISPLAY 0.468085 (-7650 500);
PAINT GREEN (-7650 500);
DISPLAY INVISIBLE (-7650 500);
FORCEPROP 2 LAST CDS_LIB cls
J 0
(-7650 500);
DISPLAY INVISIBLE (-7650 500);
FORCEPROP 1 LAST BODY_TYPE PLUMBING
J 0
(-7635 485);
DISPLAY 0.808511 (-7635 485);
PAINT GREEN (-7635 485);
DISPLAY INVISIBLE (-7635 485);
FORCEADD GND_SG..1
(-5150 -400);
FORCEPROP 3 LASTPIN (-5100 -350) SIG_NAME SG\g
J 0
(-5090 -340);
DISPLAY 0.659574 (-5090 -340);
PAINT MONO (-5090 -340);
DISPLAY INVISIBLE (-5090 -340);
FORCEPROP 1 LAST HDL_POWER SG
J 1
(-5095 -495);
DISPLAY 0.808511 (-5095 -495);
PAINT GREEN (-5095 -495);
FORCEPROP 1 LAST PATH I478
J 0
(-5115 -400);
DISPLAY 0.808511 (-5115 -400);
PAINT GREEN (-5115 -400);
DISPLAY INVISIBLE (-5115 -400);
FORCEPROP 1 LAST BODY_TYPE PLUMBING
J 0
(-5135 -415);
DISPLAY 0.808511 (-5135 -415);
PAINT GREEN (-5135 -415);
DISPLAY INVISIBLE (-5135 -415);
FORCEPROP 1 LAST CDS_LMAN_SYM_OUTLINE 0,0,100,-50
J 0
(-5150 -400);
DISPLAY 0.468085 (-5150 -400);
PAINT GREEN (-5150 -400);
DISPLAY INVISIBLE (-5150 -400);
FORCEPROP 2 LAST CDS_LIB cls
J 0
(-5150 -400);
DISPLAY INVISIBLE (-5150 -400);
FORCEADD GND_SG..1
(-6450 -500);
FORCEPROP 3 LASTPIN (-6400 -450) SIG_NAME SG\g
J 0
(-6390 -440);
DISPLAY 0.659574 (-6390 -440);
PAINT MONO (-6390 -440);
DISPLAY INVISIBLE (-6390 -440);
FORCEPROP 1 LAST HDL_POWER SG
J 1
(-6395 -595);
DISPLAY 0.808511 (-6395 -595);
PAINT GREEN (-6395 -595);
FORCEPROP 1 LAST BODY_TYPE PLUMBING
J 0
(-6435 -515);
DISPLAY 0.808511 (-6435 -515);
PAINT GREEN (-6435 -515);
DISPLAY INVISIBLE (-6435 -515);
FORCEPROP 1 LAST CDS_LMAN_SYM_OUTLINE 0,0,100,-50
J 0
(-6450 -500);
DISPLAY 0.468085 (-6450 -500);
PAINT GREEN (-6450 -500);
DISPLAY INVISIBLE (-6450 -500);
FORCEPROP 2 LAST CDS_LIB cls
J 0
(-6450 -500);
DISPLAY INVISIBLE (-6450 -500);
FORCEPROP 1 LAST PATH I479
J 0
(-6415 -500);
DISPLAY 0.808511 (-6415 -500);
PAINT GREEN (-6415 -500);
DISPLAY INVISIBLE (-6415 -500);
FORCEADD OFFPAGE_IN..2
(-4300 5050);
FORCEPROP 2 LAST $XR0 25C9<> 
J 0
(-4250 5050);
DISPLAY 0.638298 (-4250 5050);
PAINT MONO (-4250 5050);
FORCEPROP 2 LAST $XR1 26D8< 
J 0
(-4050 5050);
DISPLAY 0.638298 (-4050 5050);
PAINT MONO (-4050 5050);
FORCEPROP 1 LAST OFFPAGE TRUE
J 0
(-4290 5105);
DISPLAY 0.808511 (-4290 5105);
PAINT GREEN (-4290 5105);
DISPLAY INVISIBLE (-4290 5105);
FORCEPROP 1 LAST BODY_TYPE COMMENT
J 0
(-4290 5185);
DISPLAY 0.808511 (-4290 5185);
PAINT GREEN (-4290 5185);
DISPLAY INVISIBLE (-4290 5185);
FORCEPROP 1 LAST CDS_LMAN_SYM_OUTLINE -50,50,50,-50
J 0
(-4300 5050);
DISPLAY 0.468085 (-4300 5050);
PAINT GREEN (-4300 5050);
DISPLAY INVISIBLE (-4300 5050);
FORCEPROP 2 LAST CDS_LIB cls
J 0
(-4300 5050);
DISPLAY INVISIBLE (-4300 5050);
FORCEPROP 2 LAST PATH I480
J 0
(-4250 5150);
DISPLAY 1.021277 (-4250 5150);
DISPLAY INVISIBLE (-4250 5150);
FORCEADD OFFPAGE_IN..1
(-9100 5950);
FORCEPROP 2 LAST $XR0 25C9<> 
J 0
(-9314 5950);
DISPLAY 0.638298 (-9314 5950);
PAINT MONO (-9314 5950);
FORCEPROP 1 LAST OFFPAGE TRUE
J 0
(-9090 6005);
DISPLAY 0.808511 (-9090 6005);
PAINT GREEN (-9090 6005);
DISPLAY INVISIBLE (-9090 6005);
FORCEPROP 1 LAST BODY_TYPE COMMENT
J 0
(-9090 6085);
DISPLAY 0.808511 (-9090 6085);
PAINT GREEN (-9090 6085);
DISPLAY INVISIBLE (-9090 6085);
FORCEPROP 1 LAST CDS_LMAN_SYM_OUTLINE -50,50,50,-50
J 0
(-9100 5950);
DISPLAY 0.468085 (-9100 5950);
PAINT GREEN (-9100 5950);
DISPLAY INVISIBLE (-9100 5950);
FORCEPROP 2 LAST PATH I481
J 0
(-9050 6050);
DISPLAY 1.021277 (-9050 6050);
DISPLAY INVISIBLE (-9050 6050);
FORCEPROP 2 LAST CDS_LIB cls
J 0
(-9100 5950);
DISPLAY INVISIBLE (-9100 5950);
FORCEADD OFFPAGE_OUT..1
R 2
(-3100 3000);
FORCEPROP 2 LAST $XR0 10E12< 
J 0
(-3314 3000);
DISPLAY 0.638298 (-3314 3000);
PAINT MONO (-3314 3000);
FORCEPROP 1 LAST BODY_TYPE COMMENT
J 2
(-3110 3135);
DISPLAY 0.808511 (-3110 3135);
PAINT GREEN (-3110 3135);
DISPLAY INVISIBLE (-3110 3135);
FORCEPROP 1 LAST CDS_LMAN_SYM_OUTLINE -50,50,50,-50
J 2
(-3100 3000);
DISPLAY 0.468085 (-3100 3000);
PAINT GREEN (-3100 3000);
DISPLAY INVISIBLE (-3100 3000);
FORCEPROP 2 LAST CDS_LIB cls
J 0
(-3100 3000);
PAINT MONO (-3100 3000);
DISPLAY INVISIBLE (-3100 3000);
FORCEPROP 1 LAST OFFPAGE TRUE
J 2
(-3110 3055);
DISPLAY 0.808511 (-3110 3055);
PAINT GREEN (-3110 3055);
DISPLAY INVISIBLE (-3110 3055);
FORCEPROP 2 LAST PATH I71
J 0
(-3200 3050);
DISPLAY 1.021277 (-3200 3050);
DISPLAY INVISIBLE (-3200 3050);
FORCEADD OFFPAGE_OUT..1
R 2
(-3100 2800);
FORCEPROP 2 LAST $XR0 10E12< 
J 0
(-3314 2800);
DISPLAY 0.638298 (-3314 2800);
PAINT MONO (-3314 2800);
FORCEPROP 1 LAST BODY_TYPE COMMENT
J 2
(-3110 2935);
DISPLAY 0.808511 (-3110 2935);
PAINT GREEN (-3110 2935);
DISPLAY INVISIBLE (-3110 2935);
FORCEPROP 1 LAST CDS_LMAN_SYM_OUTLINE -50,50,50,-50
J 2
(-3100 2800);
DISPLAY 0.468085 (-3100 2800);
PAINT GREEN (-3100 2800);
DISPLAY INVISIBLE (-3100 2800);
FORCEPROP 2 LAST CDS_LIB cls
J 0
(-3100 2800);
PAINT MONO (-3100 2800);
DISPLAY INVISIBLE (-3100 2800);
FORCEPROP 1 LAST OFFPAGE TRUE
J 2
(-3110 2855);
DISPLAY 0.808511 (-3110 2855);
PAINT GREEN (-3110 2855);
DISPLAY INVISIBLE (-3110 2855);
FORCEPROP 2 LAST PATH I72
J 0
(-3200 2850);
DISPLAY 1.021277 (-3200 2850);
DISPLAY INVISIBLE (-3200 2850);
FORCEADD OFFPAGE_OUT..1
R 2
(-3100 2900);
FORCEPROP 2 LAST $XR0 10E12< 
J 0
(-3314 2900);
DISPLAY 0.638298 (-3314 2900);
PAINT MONO (-3314 2900);
FORCEPROP 2 LAST CDS_LIB cls
J 0
(-3100 2900);
PAINT MONO (-3100 2900);
DISPLAY INVISIBLE (-3100 2900);
FORCEPROP 1 LAST CDS_LMAN_SYM_OUTLINE -50,50,50,-50
J 2
(-3100 2900);
DISPLAY 0.468085 (-3100 2900);
PAINT GREEN (-3100 2900);
DISPLAY INVISIBLE (-3100 2900);
FORCEPROP 1 LAST BODY_TYPE COMMENT
J 2
(-3110 3035);
DISPLAY 0.808511 (-3110 3035);
PAINT GREEN (-3110 3035);
DISPLAY INVISIBLE (-3110 3035);
FORCEPROP 1 LAST OFFPAGE TRUE
J 2
(-3110 2955);
DISPLAY 0.808511 (-3110 2955);
PAINT GREEN (-3110 2955);
DISPLAY INVISIBLE (-3110 2955);
FORCEPROP 2 LAST PATH I73
J 0
(-3200 2950);
DISPLAY 1.021277 (-3200 2950);
DISPLAY INVISIBLE (-3200 2950);
FORCEADD GND_SG..1
(-1050 2200);
FORCEPROP 3 LASTPIN (-1000 2250) SIG_NAME SG\g
J 0
(-990 2260);
DISPLAY 0.659574 (-990 2260);
PAINT MONO (-990 2260);
DISPLAY INVISIBLE (-990 2260);
FORCEPROP 1 LAST HDL_POWER SG
J 1
(-995 2105);
DISPLAY 0.808511 (-995 2105);
PAINT GREEN (-995 2105);
FORCEPROP 1 LAST CDS_LMAN_SYM_OUTLINE 0,0,100,-50
J 0
(-1050 2200);
DISPLAY 0.468085 (-1050 2200);
PAINT GREEN (-1050 2200);
DISPLAY INVISIBLE (-1050 2200);
FORCEPROP 2 LAST CDS_LIB cls
J 0
(-1050 2200);
PAINT MONO (-1050 2200);
DISPLAY INVISIBLE (-1050 2200);
FORCEPROP 1 LAST BODY_TYPE PLUMBING
J 0
(-1035 2185);
DISPLAY 0.808511 (-1035 2185);
PAINT GREEN (-1035 2185);
DISPLAY INVISIBLE (-1035 2185);
FORCEPROP 1 LAST PATH I75
J 0
(-1015 2200);
DISPLAY 0.808511 (-1015 2200);
PAINT GREEN (-1015 2200);
DISPLAY INVISIBLE (-1015 2200);
FORCEADD SHEET_A1..1
(150 -1550);
FORCEPROP 2 LAST CUSTOM_TXT_CDS <XR_PAGE_TITLE>
J 0
(-15420 9800);
DISPLAY 0.638298 (-15420 9800);
PAINT PINK (-15420 9800);
FORCEPROP 1 LAST CUSTOM_TXT_CDS <DOCNO>
J 0
(-1900 -1165);
DISPLAY 0.978723 (-1900 -1165);
FORCEPROP 1 LAST CUSTOM_TXT_CDS <CON_PAGE_NUM>
J 0
(-2005 -1500);
DISPLAY 0.978723 (-2005 -1500);
FORCEPROP 1 LAST CUSTOM_TXT_CDS <DATE>
J 0
(-550 -1375);
DISPLAY 0.978723 (-550 -1375);
FORCEPROP 1 LAST CUSTOM_TXT_CDS <TITLE>
J 1
(-1635 -920);
DISPLAY 0.978723 (-1635 -920);
FORCEPROP 1 LAST CUSTOM_TXT_CDS <DESIGNER>
J 0
(-550 -950);
DISPLAY 0.978723 (-550 -950);
FORCEPROP 1 LAST CUSTOM_TXT_CDS <CON_TOTAL_PAGES>
J 0
(-1695 -1500);
DISPLAY 0.808511 (-1695 -1500);
FORCEPROP 1 LAST CUSTOM_TXT_CDS <ASSY_PN>
J 0
(-1900 -1375);
DISPLAY 0.978723 (-1900 -1375);
FORCEPROP 1 LAST CUSTOM_TXT_CDS <DOCREV>
J 0
(-550 -1175);
DISPLAY 0.978723 (-550 -1175);
FORCEPROP 1 LAST TITLE FPGA_1/5
J 0
(-2350 -650);
DISPLAY 3.042553 (-2350 -650);
PAINT GREEN (-2350 -650);
FORCEPROP 2 LAST CDS_XR_PAGE_TITLE CR-10 : @TIMECARD_LIB.TIMECARD(SCH_1):PAGE10
J 0
(-15420 9800);
DISPLAY 0.638298 (-15420 9800);
PAINT PINK (-15420 9800);
DISPLAY INVISIBLE (-15420 9800);
FORCEPROP 2 LAST CDS_LIB cls
J 0
(150 -1550);
DISPLAY INVISIBLE (150 -1550);
FORCEPROP 1 LAST CDS_LMAN_SYM_OUTLINE -15850,11500,200,-200
J 0
(150 -1550);
DISPLAY 0.468085 (150 -1550);
PAINT GREEN (150 -1550);
DISPLAY INVISIBLE (150 -1550);
FORCEPROP 2 LAST PAGE_BORDER TRUE
J 0
(-15420 9800);
DISPLAY 0.638298 (-15420 9800);
PAINT PINK (-15420 9800);
DISPLAY INVISIBLE (-15420 9800);
FORCEPROP 1 LAST COMMENT_BODY TRUE
J 0
(160 -1495);
DISPLAY 0.808511 (160 -1495);
DISPLAY INVISIBLE (160 -1495);
WIRE 16 -1 (-1000 2300)(-1000 2250);
WIRE 16 -1 (-1000 2300)(-1500 2300);
WIRE 16 -1 (-1000 2450)(-1000 2300);
WIRE 16 -1 (-6400 -350)(-6400 -450);
WIRE 16 -1 (-5100 -350)(-5100 -250);
WIRE 16 -1 (-7600 600)(-7600 550);
WIRE 16 -1 (-7000 600)(-7600 600);
WIRE 16 -1 (-7600 750)(-7600 600);
WIRE 16 -1 (-7600 1200)(-7600 1150);
WIRE 16 -1 (-3750 700)(-3750 800);
WIRE 16 -1 (-3750 600)(-3750 700);
WIRE 16 -1 (-4350 700)(-3750 700);
WIRE 16 -1 (-14500 350)(-14500 500);
WIRE 16 -1 (-14500 350)(-14400 350);
WIRE 16 -1 (-14000 -450)(-14000 -250);
WIRE 16 -1 (-12150 -450)(-12150 -400);
WIRE 16 -1 (-10250 650)(-10250 500);
WIRE 16 -1 (-10450 2350)(-10450 2250);
WIRE 16 -1 (-4550 3550)(-4550 3450);
WIRE 16 -1 (-4550 2350)(-4550 2300);
WIRE 16 -1 (-4550 2350)(-5000 2350);
WIRE 16 -1 (-4550 2450)(-4550 2350);
WIRE 16 -1 (-2650 4850)(-2650 4750);
WIRE 16 -1 (-1000 3450)(-1000 3600);
WIRE 16 -1 (-1000 3450)(-1500 3450);
WIRE 16 -1 (-1000 3350)(-1000 3450);
WIRE 16 -1 (-11750 4650)(-11750 5550);
WIRE 16 -1 (-11750 4650)(-11000 4650);
WIRE 16 -1 (-10650 5800)(-10650 5900);
WIRE 16 -1 (-10650 5800)(-10250 5800);
WIRE 16 -1 (-6300 5850)(-6300 5800);
WIRE 16 -1 (-6500 5850)(-6300 5850);
WIRE 16 -1 (-9000 5550)(-9000 5650);
WIRE 16 -1 (-2000 2300)(-2000 2450);
WIRE 16 -1 (-2000 2300)(-1500 2300);
WIRE 16 -1 (-1500 2450)(-1500 2300);
WIRE 16 -1 (-5100 -250)(-5200 -250);
WIRE 16 -1 (-7000 750)(-7000 600);
WIRE 16 -1 (-6200 450)(-6300 450);
WIRE 16 -1 (-6300 700)(-6300 450);
WIRE 16 -1 (-6500 600)(-6500 700);
WIRE 16 -1 (-6500 700)(-6300 700);
WIRE 16 -1 (-6500 1150)(-6500 700);
WIRE 16 -1 (-7000 1150)(-7000 1000);
WIRE 16 -1 (-6500 1150)(-7000 1150);
WIRE 16 -1 (-7000 1150)(-7600 1150);
WIRE 16 -1 (-7600 1000)(-7600 1150);
WIRE 16 -1 (-4350 400)(-3750 400);
WIRE 16 -1 (-4350 500)(-3750 500);
WIRE 16 -1 (-3750 500)(-3750 400);
WIRE 16 -1 (-4350 600)(-3750 600);
WIRE 16 -1 (-3750 500)(-3750 600);
WIRE 16 -1 (-14000 550)(-13850 550);
WIRE 16 -1 (-14000 -250)(-13850 -250);
WIRE 16 -1 (-14000 -250)(-14000 550);
WIRE 16 -1 (-11350 -300)(-11350 -400);
WIRE 16 -1 (-12150 -300)(-12150 -400);
WIRE 16 -1 (-11350 -400)(-12150 -400);
WIRE 16 -1 (-11150 2250)(-11150 2050);
WIRE 16 -1 (-11150 2250)(-10800 2250);
WIRE 16 -1 (-10800 2050)(-10800 2250);
WIRE 16 -1 (-10450 2250)(-10800 2250);
WIRE 16 -1 (-10450 2050)(-10450 2250);
WIRE 16 -1 (-5500 3350)(-5500 3450);
WIRE 16 -1 (-5000 3450)(-5500 3450);
WIRE 16 -1 (-5000 3350)(-5000 3450);
WIRE 16 -1 (-4550 3450)(-5000 3450);
WIRE 16 -1 (-4550 3350)(-4550 3450);
WIRE 16 -1 (-5500 2450)(-5500 2350);
WIRE 16 -1 (-5000 2350)(-5500 2350);
WIRE 16 -1 (-5000 2450)(-5000 2350);
WIRE 16 -1 (-3450 4650)(-2800 4650);
WIRE 16 -1 (-2800 4750)(-3450 4750);
WIRE 16 -1 (-2800 4650)(-2800 4750);
WIRE 16 -1 (-2650 4750)(-2800 4750);
WIRE 16 -1 (-2000 3350)(-2000 3450);
WIRE 16 -1 (-1500 3450)(-1500 3350);
WIRE 16 -1 (-2000 3450)(-1500 3450);
WIRE 16 -1 (-11000 4750)(-10450 4750);
WIRE 16 -1 (-11000 4650)(-11000 4750);
WIRE 16 -1 (-10450 4650)(-11000 4650);
WIRE 16 -1 (-6500 5750)(-6650 5750);
WIRE 16 -1 (-6500 5750)(-6500 5850);
WIRE 16 -1 (-6650 5850)(-6500 5850);
WIRE 16 -1 (-8850 5450)(-8650 5450);
WIRE 16 -1 (-8650 5850)(-8850 5850);
WIRE 16 -1 (-8850 5750)(-8850 5850);
WIRE 16 -1 (-8650 5750)(-8850 5750);
WIRE 16 -1 (-8850 5550)(-8850 5450);
WIRE 16 -1 (-8850 5550)(-8650 5550);
WIRE 16 -1 (-8850 5550)(-8850 5650);
WIRE 16 -1 (-8850 5650)(-8850 5750);
WIRE 16 -1 (-8850 5650)(-9000 5650);
WIRE 16 -1 (-11650 1050)(-10450 1050);
WIRE 16 -1 (-10450 1800)(-10450 1050);
WIRE 16 -1 (-9450 1050)(-10450 1050);
FORCEPROP 2 LAST SIG_NAME FPGA_TDI
J 0
(-9860 1060);
DISPLAY 1.021277 (-9860 1060);
WIRE 16 -1 (-11050 -400)(-11050 -300);
WIRE 16 -1 (-10750 -400)(-11050 -400);
WIRE 16 -1 (-10750 700)(-10750 -400);
WIRE 16 -1 (-13150 550)(-12700 550);
WIRE 16 -1 (-12700 550)(-12700 700);
WIRE 16 -1 (-12700 700)(-10750 700);
WIRE 16 -1 (-12700 700)(-12700 1600);
WIRE 16 -1 (-11900 1600)(-12700 1600);
WIRE 16 -1 (-14350 1600)(-12700 1600);
FORCEPROP 2 LAST SIG_NAME FT4232_FPGA_TCK
J 0
(-14310 1610);
DISPLAY 1.021277 (-14310 1610);
WIRE 16 -1 (-11900 300)(-11900 400);
WIRE 16 -1 (-13150 -250)(-12400 -250);
WIRE 16 -1 (-12400 -250)(-12400 400);
WIRE 16 -1 (-11900 400)(-12400 400);
WIRE 16 -1 (-12400 400)(-12400 1050);
WIRE 16 -1 (-11900 1050)(-12400 1050);
WIRE 16 -1 (-14350 1050)(-12400 1050);
FORCEPROP 2 LAST SIG_NAME FT4232_FPGA_TDI
J 0
(-14310 1060);
DISPLAY 1.021277 (-14310 1060);
WIRE 16 -1 (-11100 300)(-11100 600);
WIRE 16 -1 (-12600 350)(-13150 350);
WIRE 16 -1 (-12600 600)(-12600 350);
WIRE 16 -1 (-11100 600)(-12600 600);
WIRE 16 -1 (-12600 1400)(-12600 600);
WIRE 16 -1 (-11900 1400)(-12600 1400);
WIRE 16 -1 (-14350 1400)(-12600 1400);
FORCEPROP 2 LAST SIG_NAME FT4232_FPGA_TDO
J 0
(-14310 1410);
DISPLAY 1.021277 (-14310 1410);
WIRE 16 -1 (-11550 -300)(-11850 -300);
WIRE 16 -1 (-11550 -300)(-11550 500);
WIRE 16 -1 (-12500 150)(-13150 150);
WIRE 16 -1 (-12500 500)(-12500 150);
WIRE 16 -1 (-11550 500)(-12500 500);
WIRE 16 -1 (-12500 1200)(-12500 500);
WIRE 16 -1 (-11900 1200)(-12500 1200);
WIRE 16 -1 (-14350 1200)(-12500 1200);
FORCEPROP 2 LAST SIG_NAME FT4232_FPGA_TMS
J 0
(-14310 1210);
DISPLAY 1.021277 (-14310 1210);
WIRE 16 -1 (-4350 50)(-3050 50);
FORCEPROP 2 LAST SIG_NAME FLASH_DQ2
J 0
(-3810 60);
DISPLAY 1.021277 (-3810 60);
WIRE 16 -1 (-4350 150)(-3050 150);
FORCEPROP 2 LAST SIG_NAME FLASH_DQ1_MISO
J 0
(-3810 160);
DISPLAY 1.021277 (-3810 160);
WIRE 16 -1 (-5100 700)(-4600 700);
WIRE 16 -1 (-5200 250)(-5100 250);
WIRE 16 -1 (-5100 250)(-4600 250);
WIRE 16 -1 (-5100 250)(-5100 700);
WIRE 16 -1 (-4600 500)(-5000 500);
WIRE 16 -1 (-5000 50)(-4600 50);
WIRE 16 -1 (-5000 500)(-5000 50);
WIRE 16 -1 (-5200 50)(-5000 50);
WIRE 16 -1 (-4350 250)(-3050 250);
FORCEPROP 2 LAST SIG_NAME FLASH_DQ0_MOSI
J 0
(-3810 260);
DISPLAY 1.021277 (-3810 260);
WIRE 16 -1 (-1000 2700)(-1000 3000);
WIRE 16 -1 (-1000 3000)(-1000 3100);
WIRE 16 -1 (-3050 3000)(-1000 3000);
FORCEPROP 2 LAST SIG_NAME FPGA_M2
J 0
(-3010 3010);
DISPLAY 1.021277 (-3010 3010);
WIRE 16 -1 (-4350 -50)(-3050 -50);
FORCEPROP 2 LAST SIG_NAME FLASH_DQ3
J 0
(-3810 -40);
DISPLAY 1.021277 (-3810 -40);
WIRE 16 -1 (-6400 250)(-6400 -100);
WIRE 16 -1 (-6200 250)(-6400 250);
WIRE 16 -1 (-7700 250)(-6400 250);
FORCEPROP 2 LAST SIG_NAME FLASH_CLK
J 0
(-7660 260);
DISPLAY 1.021277 (-7660 260);
WIRE 16 -1 (-6500 350)(-6500 50);
WIRE 16 -1 (-6200 50)(-6500 50);
WIRE 16 -1 (-7700 50)(-6500 50);
FORCEPROP 2 LAST SIG_NAME FLASH_CS_N
J 0
(-7660 60);
DISPLAY 1.021277 (-7660 60);
WIRE 16 -1 (-4950 -50)(-4600 -50);
WIRE 16 -1 (-5200 -50)(-4950 -50);
WIRE 16 -1 (-4950 400)(-4950 -50);
WIRE 16 -1 (-4600 400)(-4950 400);
WIRE 16 -1 (-5050 150)(-4600 150);
WIRE 16 -1 (-5200 150)(-5050 150);
WIRE 16 -1 (-5050 600)(-5050 150);
WIRE 16 -1 (-4600 600)(-5050 600);
WIRE 16 -1 (-5850 5150)(-6650 5150);
FORCEPROP 2 LAST SIG_NAME CCLK_0
J 0
(-6460 5160);
DISPLAY 1.021277 (-6460 5160);
WIRE 16 -1 (-6650 5550)(-4350 5550);
FORCEPROP 2 LAST SIG_NAME FPGA_M0
J 0
(-4760 5560);
DISPLAY 1.021277 (-4760 5560);
WIRE 16 -1 (-2000 2700)(-2000 2800);
WIRE 16 -1 (-2000 3100)(-2000 2800);
WIRE 16 -1 (-3050 2800)(-2000 2800);
FORCEPROP 2 LAST SIG_NAME FPGA_M0
J 0
(-3010 2810);
DISPLAY 1.021277 (-3010 2810);
WIRE 16 -1 (-1500 2700)(-1500 2900);
WIRE 16 -1 (-1500 3100)(-1500 2900);
WIRE 16 -1 (-3050 2900)(-1500 2900);
FORCEPROP 2 LAST SIG_NAME FPGA_M1
J 0
(-3010 2910);
DISPLAY 1.021277 (-3010 2910);
WIRE 16 -1 (-5000 2900)(-6550 2900);
FORCEPROP 2 LAST SIG_NAME FPGA_BRD_REV1
J 0
(-6510 2910);
DISPLAY 1.021277 (-6510 2910);
WIRE 16 -1 (-5000 2900)(-5000 2700);
WIRE 16 -1 (-5000 3100)(-5000 2900);
WIRE 16 -1 (-5500 3000)(-6550 3000);
FORCEPROP 2 LAST SIG_NAME FPGA_BRD_REV2
J 0
(-6510 3010);
DISPLAY 1.021277 (-6510 3010);
WIRE 16 -1 (-5500 3000)(-5500 2700);
WIRE 16 -1 (-5500 3100)(-5500 3000);
WIRE 16 -1 (-8650 5150)(-9800 5150);
FORCEPROP 2 LAST SIG_NAME R_FPGA_TDO
J 0
(-9310 5160);
DISPLAY 1.021277 (-9310 5160);
WIRE 16 -1 (-11650 1200)(-10800 1200);
WIRE 16 -1 (-10800 1800)(-10800 1200);
WIRE 16 -1 (-9450 1200)(-10800 1200);
FORCEPROP 2 LAST SIG_NAME FPGA_TMS
J 0
(-9860 1210);
DISPLAY 1.021277 (-9860 1210);
WIRE 16 -1 (-13850 350)(-14150 350);
WIRE 16 -1 (-6650 7850)(-4300 7850);
FORCEPROP 2 LAST SIG_NAME CPU_RX_PCIE_MGT0_TXP
J 0
(-5360 7860);
DISPLAY 1.021277 (-5360 7860);
WIRE 16 -1 (-6650 7750)(-4300 7750);
FORCEPROP 2 LAST SIG_NAME CPU_RX_PCIE_MGT0_TXN
J 0
(-5360 7760);
DISPLAY 1.021277 (-5360 7760);
WIRE 16 -1 (-6650 7550)(-4300 7550);
FORCEPROP 2 LAST SIG_NAME CPU_RX_PCIE_MGT1_TXP
J 0
(-5360 7560);
DISPLAY 1.021277 (-5360 7560);
WIRE 16 -1 (-6650 7450)(-4300 7450);
FORCEPROP 2 LAST SIG_NAME CPU_RX_PCIE_MGT1_TXN
J 0
(-5360 7460);
DISPLAY 1.021277 (-5360 7460);
WIRE 16 -1 (-6650 7150)(-4300 7150);
FORCEPROP 2 LAST SIG_NAME CPU_RX_PCIE_MGT2_TXN
J 0
(-5360 7160);
DISPLAY 1.021277 (-5360 7160);
WIRE 16 -1 (-6650 7250)(-4300 7250);
FORCEPROP 2 LAST SIG_NAME CPU_RX_PCIE_MGT2_TXP
J 0
(-5360 7260);
DISPLAY 1.021277 (-5360 7260);
WIRE 16 -1 (-6650 6950)(-4300 6950);
FORCEPROP 2 LAST SIG_NAME CPU_RX_PCIE_MGT3_TXP
J 0
(-5360 6960);
DISPLAY 1.021277 (-5360 6960);
WIRE 16 -1 (-6650 6850)(-4300 6850);
FORCEPROP 2 LAST SIG_NAME CPU_RX_PCIE_MGT3_TXN
J 0
(-5360 6860);
DISPLAY 1.021277 (-5360 6860);
WIRE 16 -1 (-8650 6850)(-11400 6850);
FORCEPROP 2 LAST SIG_NAME CPU_TX_PCIE_MGT_3_RXN
J 0
(-11310 6860);
DISPLAY 1.021277 (-11310 6860);
WIRE 16 -1 (-8650 6950)(-11400 6950);
FORCEPROP 2 LAST SIG_NAME CPU_TX_PCIE_MGT_3_RXP
J 0
(-11310 6960);
DISPLAY 1.021277 (-11310 6960);
WIRE 16 -1 (-8650 7150)(-11400 7150);
FORCEPROP 2 LAST SIG_NAME CPU_TX_PCIE_MGT_2_RXN
J 0
(-11310 7160);
DISPLAY 1.021277 (-11310 7160);
WIRE 16 -1 (-8650 7250)(-11400 7250);
FORCEPROP 2 LAST SIG_NAME CPU_TX_PCIE_MGT_2_RXP
J 0
(-11310 7260);
DISPLAY 1.021277 (-11310 7260);
WIRE 16 -1 (-8650 7450)(-11400 7450);
FORCEPROP 2 LAST SIG_NAME CPU_TX_PCIE_MGT_1_RXN
J 0
(-11310 7460);
DISPLAY 1.021277 (-11310 7460);
WIRE 16 -1 (-8650 7550)(-11400 7550);
FORCEPROP 2 LAST SIG_NAME CPU_TX_PCIE_MGT_1_RXP
J 0
(-11310 7560);
DISPLAY 1.021277 (-11310 7560);
WIRE 16 -1 (-8650 7750)(-11400 7750);
FORCEPROP 2 LAST SIG_NAME CPU_TX_PCIE_MGT_0_RXN
J 0
(-11310 7760);
DISPLAY 1.021277 (-11310 7760);
WIRE 16 -1 (-8650 7850)(-11400 7850);
FORCEPROP 2 LAST SIG_NAME CPU_TX_PCIE_MGT_0_RXP
J 0
(-11310 7860);
DISPLAY 1.021277 (-11310 7860);
WIRE 16 -1 (-10050 5150)(-10950 5150);
FORCEPROP 2 LAST SIG_NAME FPGA_TDO
J 0
(-10860 5160);
DISPLAY 1.021277 (-10860 5160);
WIRE 16 -1 (-9350 6150)(-8900 6150);
WIRE 16 -1 (-8900 6150)(-8900 6250);
WIRE 16 -1 (-8900 6250)(-8650 6250);
WIRE 16 -1 (-11400 6250)(-8900 6250);
FORCEPROP 2 LAST SIG_NAME PCIE_REFCLKN
J 0
(-11310 6260);
DISPLAY 1.021277 (-11310 6260);
WIRE 16 -1 (-9600 6450)(-10000 6450);
WIRE 16 -1 (-10000 6450)(-10000 6650);
WIRE 16 -1 (-8650 6650)(-10000 6650);
WIRE 16 -1 (-11400 6650)(-10000 6650);
FORCEPROP 2 LAST SIG_NAME MHZ125CLKP_CLKIN
J 0
(-11310 6660);
DISPLAY 1.021277 (-11310 6660);
WIRE 16 -1 (-9350 6450)(-8900 6450);
WIRE 16 -1 (-8900 6450)(-8900 6550);
WIRE 16 -1 (-8900 6550)(-8650 6550);
WIRE 16 -1 (-11400 6550)(-8900 6550);
FORCEPROP 2 LAST SIG_NAME MHZ125CLKN_CLKIN
J 0
(-11310 6560);
DISPLAY 1.021277 (-11310 6560);
WIRE 16 -1 (-8950 6050)(-8650 6050);
WIRE 16 -1 (-9050 5950)(-8950 5950);
WIRE 16 -1 (-8950 5950)(-8950 6050);
WIRE 16 -1 (-8950 5800)(-8950 5950);
WIRE 16 -1 (-10000 5800)(-8950 5800);
FORCEPROP 2 LAST SIG_NAME FPGA_MGTRREF
J 0
(-9560 5810);
DISPLAY 1.021277 (-9560 5810);
WIRE 16 -1 (-6650 5450)(-4350 5450);
FORCEPROP 2 LAST SIG_NAME FPGA_M1
J 0
(-4760 5460);
DISPLAY 1.021277 (-4760 5460);
WIRE 16 -1 (-11650 1600)(-10250 1600);
WIRE 16 -1 (-10250 900)(-10250 1600);
WIRE 16 -1 (-9450 1600)(-10250 1600);
FORCEPROP 2 LAST SIG_NAME FPGA_TCK
J 0
(-9860 1610);
DISPLAY 1.021277 (-9860 1610);
WIRE 16 -1 (-6650 4950)(-4400 4950);
WIRE 16 -1 (-4350 4950)(-4400 4950);
WIRE 16 -1 (-4400 4750)(-4400 4950);
FORCEPROP 2 LAST SIG_NAME FPGA_CFG_INIT_N
J 0
(-5260 4960);
DISPLAY 1.021277 (-5260 4960);
WIRE 16 -1 (-4400 4750)(-3700 4750);
WIRE 16 -1 (-5600 5150)(-4350 5150);
FORCEPROP 2 LAST SIG_NAME FPGA_FLASH_CLK
J 0
(-5060 5160);
DISPLAY 1.021277 (-5060 5160);
WIRE 16 -1 (-6650 5350)(-4350 5350);
FORCEPROP 2 LAST SIG_NAME FPGA_M2
J 0
(-4760 5360);
DISPLAY 1.021277 (-4760 5360);
WIRE 16 -1 (-4450 4650)(-3700 4650);
WIRE 16 -1 (-4450 5050)(-6650 5050);
FORCEPROP 2 LAST SIG_NAME FPGA_DONE
J 0
(-5260 5060);
DISPLAY 1.021277 (-5260 5060);
WIRE 16 -1 (-4450 5050)(-4450 4650);
WIRE 16 -1 (-4350 5050)(-4450 5050);
WIRE 16 -1 (-11650 1400)(-11150 1400);
WIRE 16 -1 (-11150 1800)(-11150 1400);
WIRE 16 -1 (-9450 1400)(-11150 1400);
FORCEPROP 2 LAST SIG_NAME FPGA_TDO
J 0
(-9860 1410);
DISPLAY 1.021277 (-9860 1410);
WIRE 16 -1 (-10950 4850)(-8850 4850);
WIRE 16 -1 (-8850 4850)(-8850 4750);
WIRE 16 -1 (-8650 4750)(-8850 4750);
WIRE 16 -1 (-10200 4750)(-8850 4750);
FORCEPROP 2 LAST SIG_NAME FPGA_PROGRAM_N
J 0
(-10860 4860);
DISPLAY 1.021277 (-10860 4860);
WIRE 16 -1 (-10950 5050)(-8650 5050);
FORCEPROP 2 LAST SIG_NAME FPGA_TCK
J 0
(-10860 5060);
DISPLAY 1.021277 (-10860 5060);
WIRE 16 -1 (-10950 4950)(-8650 4950);
FORCEPROP 2 LAST SIG_NAME FPGA_TMS
J 0
(-10860 4960);
DISPLAY 1.021277 (-10860 4960);
WIRE 16 -1 (-10200 4650)(-8650 4650);
FORCEPROP 2 LAST SIG_NAME CFGBVS
J 0
(-9610 4660);
DISPLAY 1.021277 (-9610 4660);
WIRE 16 -1 (-9600 6150)(-10000 6150);
WIRE 16 -1 (-10000 6150)(-10000 6350);
WIRE 16 -1 (-8650 6350)(-10000 6350);
WIRE 16 -1 (-11400 6350)(-10000 6350);
FORCEPROP 2 LAST SIG_NAME PCIE_REFCLKP
J 0
(-11310 6360);
DISPLAY 1.021277 (-11310 6360);
WIRE 16 -1 (-10950 5250)(-8650 5250);
FORCEPROP 2 LAST SIG_NAME FPGA_TDI
J 0
(-10860 5260);
DISPLAY 1.021277 (-10860 5260);
WIRE 16 -1 (-4550 2800)(-6550 2800);
FORCEPROP 2 LAST SIG_NAME FPGA_BRD_REV0
J 0
(-6510 2810);
DISPLAY 1.021277 (-6510 2810);
WIRE 16 -1 (-4550 2800)(-4550 2700);
WIRE 16 -1 (-4550 3100)(-4550 2800);
DOT 1 (-3750 600);
DOT 1 (-4400 4950);
DOT 1 (-10450 2250);
DOT 1 (-10250 1600);
DOT 1 (-10800 2250);
DOT 1 (-11150 1400);
DOT 1 (-10450 1050);
DOT 1 (-10800 1200);
DOT 1 (-12600 1400);
DOT 1 (-12700 1600);
DOT 1 (-12400 1050);
DOT 1 (-12500 1200);
DOT 1 (-12600 600);
DOT 1 (-12400 400);
DOT 1 (-12500 500);
DOT 1 (-12700 700);
DOT 1 (-12150 -400);
DOT 1 (-14000 -250);
DOT 1 (-8950 5950);
DOT 1 (-8850 5750);
DOT 1 (-11000 4650);
DOT 1 (-4450 5050);
DOT 1 (-2800 4750);
DOT 1 (-8850 4750);
DOT 1 (-8850 5550);
DOT 1 (-8850 5650);
DOT 1 (-10000 6350);
DOT 1 (-10000 6650);
DOT 1 (-8900 6250);
DOT 1 (-8900 6550);
DOT 1 (-6500 5850);
DOT 1 (-5500 3000);
DOT 1 (-5000 2350);
DOT 1 (-5000 2900);
DOT 1 (-4550 2350);
DOT 1 (-4550 2800);
DOT 1 (-5000 3450);
DOT 1 (-4550 3450);
DOT 1 (-2000 2800);
DOT 1 (-1500 2300);
DOT 1 (-1500 2900);
DOT 1 (-1500 3450);
DOT 1 (-1000 2300);
DOT 1 (-1000 3000);
DOT 1 (-1000 3450);
DOT 1 (-3750 700);
DOT 1 (-3750 500);
DOT 1 (-5000 50);
DOT 1 (-5050 150);
DOT 1 (-5100 250);
DOT 1 (-7000 1150);
DOT 1 (-6500 700);
DOT 1 (-6500 50);
DOT 1 (-6400 250);
DOT 1 (-7600 1150);
DOT 1 (-7600 600);
DOT 1 (-4950 -50);
FORCENOTE
FPGA_JTAG_CONN
(-14150 2050) 0;
DISPLAY LEFT (-14150 2050);
DISPLAY 3.851064 (-14150 2050);
FORCENOTE
- THE FLASHROM TOOL (FTDI<>SPI FLASH) DOES NOT SUPPORT YET FOR THE SPI FLASH CPN:G221-10224-01 MPN:MT25QL128ABA1ESE-0SIT.
(-6300 1400) 0;
DISPLAY LEFT (-6300 1400);
DISPLAY 1.021277 (-6300 1400);
FORCENOTE
THUS, CHANGE THE SPI FLASH CPN:G221-10224-01 MPN:MT25QL128ABA1ESE-0SIT TO CPN:G221-10359-01 MPN:MX25L25645GM2I-08G.
(-6200 1300) 0;
DISPLAY LEFT (-6200 1300);
DISPLAY 1.021277 (-6200 1300);
FORCENOTE
- CHANGE CPN:G221-10224-01 MPN:MT25QL128ABA1ESE-0SIT TO CPN:G221-10359-01 MPN:MX25L25645GM2I-08G.
(-5750 1150) 0;
DISPLAY LEFT (-5750 1150);
DISPLAY 1.021277 (-5750 1150);
FORCENOTE
- SCHEMATIC RELEASE DATE: JUL 05, 2022.
(-6300 1500) 0;
DISPLAY LEFT (-6300 1500);
DISPLAY 1.021277 (-6300 1500);
FORCENOTE
REV 3.0 [PVT]:
(-7150 1500) 0;
DISPLAY LEFT (-7150 1500);
DISPLAY 1.276596 (-7150 1500);
FORCENOTE
FPGA 1/5
(-8350 8850) 0;
DISPLAY LEFT (-8350 8850);
DISPLAY 3.936170 (-8350 8850);
FORCENOTE
JTAG MODE:101  SPI MODE:001
(-3750 2650) 0;
DISPLAY LEFT (-3750 2650);
DISPLAY 1.276596 (-3750 2650);
FORCENOTE
- BOM NOTE:
(-6300 1150) 0;
DISPLAY LEFT (-6300 1150);
DISPLAY 1.021277 (-6300 1150);
FORCENOTE
000 = PCB CPN: R4006-B0001-01_R01.
(-7700 2550) 0;
DISPLAY LEFT (-7700 2550);
DISPLAY 1.276596 (-7700 2550);
FORCENOTE
BOARD_REV:
(-7700 2700) 0;
DISPLAY LEFT (-7700 2700);
DISPLAY 1.276596 (-7700 2700);
FORCENOTE
001 = PCB CPN: R4006-B0001-02_R01.
(-7700 2450) 0;
DISPLAY LEFT (-7700 2450);
DISPLAY 1.276596 (-7700 2450);
QUIT
